G04 ================== begin FILE IDENTIFICATION RECORD ==================*
G04 Layout Name:  15105-sa.brd*
G04 Film Name:    SE_REF_L1*
G04 File Format:  Gerber RS274X*
G04 File Origin:  Cadence Allegro 16.5-S056*
G04 Origin Date:  Wed Nov 16 02:02:34 2016*
G04 *
G04 Layer:  BOARD GEOMETRY/SE_REF_L1_TBL*
G04 Layer:  BOARD GEOMETRY/SE_REF_L1_TOP*
G04 Layer:  BOARD GEOMETRY/PANEL_OUTLINE*
G04 *
G04 Offset:    (0.00 0.00)*
G04 Mirror:    No*
G04 Mode:      Positive*
G04 Rotation:  0*
G04 FullContactRelief:  No*
G04 UndefLineWidth:     6.00*
G04 ================== end FILE IDENTIFICATION RECORD ====================*
%FSLAX35Y35*MOIN*%
%IR0*IPPOS*OFA0.00000B0.00000*MIA0B0*SFA1.00000B1.00000*%
%ADD10C,.02*%
%ADD11C,.006*%
%ADD12C,.00475*%
G75*
%LPD*%
G75*
G54D10*
G01X1479970Y793988D02*
X2197470D01*
G01X1479970Y863288D02*
Y793988D01*
G01Y828638D02*
X2197470D01*
G01X1479970Y863288D02*
X2197470D01*
G01X1654970D02*
Y793988D01*
G01X1882470Y863288D02*
Y793988D01*
G01X1987470Y863288D02*
Y793988D01*
G01X2197470Y863288D02*
Y793988D01*
G54D11*
G01X-27072Y-83981D02*
Y-101481D01*
G01X-32094Y-83981D02*
X-22050D01*
G01X-13284Y-101481D02*
Y-83981D01*
G01Y-92439D02*
X-12192Y-90981D01*
X-11100Y-90106D01*
X-9354Y-89815D01*
X-8044Y-90106D01*
X-6515Y-91273D01*
X-5860Y-93023D01*
Y-101481D01*
G01X7928Y-89815D02*
Y-101481D01*
G01Y-85148D02*
X7491Y-84856D01*
Y-84273D01*
X7928Y-83981D01*
X8365Y-84273D01*
Y-84856D01*
X7928Y-85148D01*
G01X22153Y-99440D02*
X23245Y-100606D01*
X24773Y-101481D01*
X26083D01*
X27393Y-100898D01*
X28266Y-100023D01*
X28703Y-98857D01*
X28485Y-97106D01*
X27611Y-96231D01*
X23681Y-94481D01*
X22808Y-92439D01*
X23245Y-90981D01*
X24118Y-90106D01*
X25428Y-89815D01*
X26738Y-90106D01*
X28048Y-90981D01*
G01X57371Y-105856D02*
X58900Y-107023D01*
X60646Y-107314D01*
X62174Y-107023D01*
X63485Y-105565D01*
X64358Y-103523D01*
Y-89815D01*
G01Y-92148D02*
X63485Y-90981D01*
X62174Y-90106D01*
X60646Y-89815D01*
X58900Y-90398D01*
X57808Y-91564D01*
X56934Y-93606D01*
X56498Y-95648D01*
X56716Y-97398D01*
X57590Y-99440D01*
X58900Y-100898D01*
X60646Y-101481D01*
X61956Y-101189D01*
X63485Y-100023D01*
X64358Y-98857D01*
G01X74653Y-93606D02*
X81640D01*
X80985Y-91564D01*
X79893Y-90398D01*
X78365Y-89815D01*
X76836Y-90106D01*
X75526Y-90981D01*
X74653Y-93023D01*
X74216Y-94773D01*
Y-96523D01*
X74653Y-98273D01*
X75745Y-100023D01*
X77055Y-101189D01*
X78583Y-101481D01*
X80111Y-100898D01*
X81640Y-99148D01*
G01X92371Y-101481D02*
Y-89815D01*
G01Y-92148D02*
X93463Y-90981D01*
X94555Y-90106D01*
X96083Y-89815D01*
X97174Y-90106D01*
X98485Y-90981D01*
G01X108998Y-101481D02*
Y-83981D01*
G01Y-92731D02*
X110090Y-90981D01*
X111400Y-90106D01*
X112710Y-89815D01*
X114674Y-90398D01*
X115985Y-91564D01*
X116858Y-93606D01*
Y-95939D01*
X116421Y-98273D01*
X115548Y-100023D01*
X114020Y-101189D01*
X112710Y-101481D01*
X111400Y-101189D01*
X110090Y-100315D01*
X108998Y-98857D01*
G01X127153Y-93606D02*
X134140D01*
X133485Y-91564D01*
X132393Y-90398D01*
X130865Y-89815D01*
X129336Y-90106D01*
X128026Y-90981D01*
X127153Y-93023D01*
X126716Y-94773D01*
Y-96523D01*
X127153Y-98273D01*
X128245Y-100023D01*
X129555Y-101189D01*
X131083Y-101481D01*
X132611Y-100898D01*
X134140Y-99148D01*
G01X144871Y-101481D02*
Y-89815D01*
G01Y-92148D02*
X145963Y-90981D01*
X147055Y-90106D01*
X148583Y-89815D01*
X149674Y-90106D01*
X150985Y-90981D01*
G01X182928Y-89815D02*
Y-101481D01*
G01Y-85148D02*
X182491Y-84856D01*
Y-84273D01*
X182928Y-83981D01*
X183365Y-84273D01*
Y-84856D01*
X182928Y-85148D01*
G01X197153Y-99440D02*
X198245Y-100606D01*
X199773Y-101481D01*
X201083D01*
X202393Y-100898D01*
X203266Y-100023D01*
X203703Y-98857D01*
X203485Y-97106D01*
X202611Y-96231D01*
X198681Y-94481D01*
X197808Y-92439D01*
X198245Y-90981D01*
X199118Y-90106D01*
X200428Y-89815D01*
X201738Y-90106D01*
X203048Y-90981D01*
G01X231934Y-105856D02*
X233463Y-107023D01*
X234773Y-107314D01*
X236520Y-106731D01*
X237830Y-105273D01*
X238485Y-102647D01*
Y-89815D01*
G01Y-85148D02*
X238048Y-84856D01*
Y-84273D01*
X238485Y-83981D01*
X238921Y-84273D01*
Y-84856D01*
X238485Y-85148D01*
G01X249216Y-89815D02*
Y-97981D01*
X250090Y-100023D01*
X251400Y-101189D01*
X252928Y-101481D01*
X254456Y-101189D01*
X255766Y-100023D01*
X256640Y-97981D01*
G01Y-101481D02*
Y-89815D01*
G01X267153Y-99440D02*
X268245Y-100606D01*
X269773Y-101481D01*
X271083D01*
X272393Y-100898D01*
X273266Y-100023D01*
X273703Y-98857D01*
X273485Y-97106D01*
X272611Y-96231D01*
X268681Y-94481D01*
X267808Y-92439D01*
X268245Y-90981D01*
X269118Y-90106D01*
X270428Y-89815D01*
X271738Y-90106D01*
X273048Y-90981D01*
G01X287928Y-83981D02*
Y-101481D01*
G01X284871Y-89815D02*
X290985D01*
G01X321618Y-101481D02*
Y-86606D01*
X322055Y-85148D01*
X322928Y-84273D01*
X324238Y-83981D01*
X325548Y-84564D01*
X326203Y-86023D01*
G01X323583Y-90981D02*
X319216D01*
G01X340428Y-101481D02*
X339118Y-101189D01*
X337808Y-100023D01*
X336934Y-97981D01*
X336498Y-95648D01*
X336934Y-93314D01*
X337808Y-91273D01*
X339118Y-90106D01*
X340428Y-89815D01*
X341738Y-90106D01*
X343048Y-91273D01*
X343921Y-93314D01*
X344140Y-95648D01*
X343921Y-97981D01*
X343048Y-100023D01*
X341738Y-101189D01*
X340428Y-101481D01*
G01X354871D02*
Y-89815D01*
G01Y-92148D02*
X355963Y-90981D01*
X357055Y-90106D01*
X358583Y-89815D01*
X359674Y-90106D01*
X360985Y-90981D01*
G01X388343Y-106731D02*
X389653Y-107314D01*
X391400Y-106731D01*
X392491Y-105565D01*
X393365Y-104106D01*
X394674Y-99440D01*
X397513Y-89815D01*
G01X390526D02*
X394674Y-99440D01*
G01X410428Y-101481D02*
X409118Y-101189D01*
X407808Y-100023D01*
X406934Y-97981D01*
X406498Y-95648D01*
X406934Y-93314D01*
X407808Y-91273D01*
X409118Y-90106D01*
X410428Y-89815D01*
X411738Y-90106D01*
X413048Y-91273D01*
X413921Y-93314D01*
X414140Y-95648D01*
X413921Y-97981D01*
X413048Y-100023D01*
X411738Y-101189D01*
X410428Y-101481D01*
G01X424216Y-89815D02*
Y-97981D01*
X425090Y-100023D01*
X426400Y-101189D01*
X427928Y-101481D01*
X429456Y-101189D01*
X430766Y-100023D01*
X431640Y-97981D01*
G01Y-101481D02*
Y-89815D01*
G01X442371Y-101481D02*
Y-89815D01*
G01Y-92148D02*
X443463Y-90981D01*
X444555Y-90106D01*
X446083Y-89815D01*
X447174Y-90106D01*
X448485Y-90981D01*
G01X477371Y-101481D02*
Y-89815D01*
G01Y-92148D02*
X478463Y-90981D01*
X479555Y-90106D01*
X481083Y-89815D01*
X482174Y-90106D01*
X483485Y-90981D01*
G01X494653Y-93606D02*
X501640D01*
X500985Y-91564D01*
X499893Y-90398D01*
X498365Y-89815D01*
X496836Y-90106D01*
X495526Y-90981D01*
X494653Y-93023D01*
X494216Y-94773D01*
Y-96523D01*
X494653Y-98273D01*
X495745Y-100023D01*
X497055Y-101189D01*
X498583Y-101481D01*
X500111Y-100898D01*
X501640Y-99148D01*
G01X514118Y-101481D02*
Y-86606D01*
X514555Y-85148D01*
X515428Y-84273D01*
X516738Y-83981D01*
X518048Y-84564D01*
X518703Y-86023D01*
G01X516083Y-90981D02*
X511716D01*
G01X529653Y-93606D02*
X536640D01*
X535985Y-91564D01*
X534893Y-90398D01*
X533365Y-89815D01*
X531836Y-90106D01*
X530526Y-90981D01*
X529653Y-93023D01*
X529216Y-94773D01*
Y-96523D01*
X529653Y-98273D01*
X530745Y-100023D01*
X532055Y-101189D01*
X533583Y-101481D01*
X535111Y-100898D01*
X536640Y-99148D01*
G01X547371Y-101481D02*
Y-89815D01*
G01Y-92148D02*
X548463Y-90981D01*
X549555Y-90106D01*
X551083Y-89815D01*
X552174Y-90106D01*
X553485Y-90981D01*
G01X564653Y-93606D02*
X571640D01*
X570985Y-91564D01*
X569893Y-90398D01*
X568365Y-89815D01*
X566836Y-90106D01*
X565526Y-90981D01*
X564653Y-93023D01*
X564216Y-94773D01*
Y-96523D01*
X564653Y-98273D01*
X565745Y-100023D01*
X567055Y-101189D01*
X568583Y-101481D01*
X570111Y-100898D01*
X571640Y-99148D01*
G01X581716Y-101481D02*
Y-89815D01*
G01Y-92731D02*
X582590Y-91273D01*
X583900Y-90106D01*
X585646Y-89815D01*
X587174Y-90106D01*
X588485Y-91273D01*
X589140Y-93314D01*
Y-101481D01*
G01X606421Y-91273D02*
X604893Y-90106D01*
X603583Y-89815D01*
X601836Y-90398D01*
X600526Y-91564D01*
X599653Y-93606D01*
X599434Y-95648D01*
X599653Y-97690D01*
X600526Y-99440D01*
X601836Y-100898D01*
X603583Y-101481D01*
X605111Y-100898D01*
X606421Y-99731D01*
G01X617153Y-93606D02*
X624140D01*
X623485Y-91564D01*
X622393Y-90398D01*
X620865Y-89815D01*
X619336Y-90106D01*
X618026Y-90981D01*
X617153Y-93023D01*
X616716Y-94773D01*
Y-96523D01*
X617153Y-98273D01*
X618245Y-100023D01*
X619555Y-101189D01*
X621083Y-101481D01*
X622611Y-100898D01*
X624140Y-99148D01*
G01X655428Y-83981D02*
Y-101481D01*
G01X652371Y-89815D02*
X658485D01*
G01X672928Y-101481D02*
X671618Y-101189D01*
X670308Y-100023D01*
X669434Y-97981D01*
X668998Y-95648D01*
X669434Y-93314D01*
X670308Y-91273D01*
X671618Y-90106D01*
X672928Y-89815D01*
X674238Y-90106D01*
X675548Y-91273D01*
X676421Y-93314D01*
X676640Y-95648D01*
X676421Y-97981D01*
X675548Y-100023D01*
X674238Y-101189D01*
X672928Y-101481D01*
G01X706618D02*
Y-86606D01*
X707055Y-85148D01*
X707928Y-84273D01*
X709238Y-83981D01*
X710548Y-84564D01*
X711203Y-86023D01*
G01X708583Y-90981D02*
X704216D01*
G01X725428Y-89815D02*
Y-101481D01*
G01Y-85148D02*
X724991Y-84856D01*
Y-84273D01*
X725428Y-83981D01*
X725865Y-84273D01*
Y-84856D01*
X725428Y-85148D01*
G01X739216Y-101481D02*
Y-89815D01*
G01Y-92731D02*
X740090Y-91273D01*
X741400Y-90106D01*
X743146Y-89815D01*
X744674Y-90106D01*
X745985Y-91273D01*
X746640Y-93314D01*
Y-101481D01*
G01X764358Y-83981D02*
Y-101481D01*
G01Y-98857D02*
X763485Y-100315D01*
X762174Y-101189D01*
X760646Y-101481D01*
X758900Y-100898D01*
X757590Y-99440D01*
X756716Y-97690D01*
X756498Y-95648D01*
X756716Y-93606D01*
X757590Y-91856D01*
X758900Y-90398D01*
X760646Y-89815D01*
X762174Y-90106D01*
X763266Y-90690D01*
X764358Y-91856D01*
G01X795428Y-83981D02*
Y-101481D01*
G01X792371Y-89815D02*
X798485D01*
G01X809216Y-101481D02*
Y-83981D01*
G01Y-92439D02*
X810308Y-90981D01*
X811400Y-90106D01*
X813146Y-89815D01*
X814456Y-90106D01*
X815985Y-91273D01*
X816640Y-93023D01*
Y-101481D01*
G01X827153Y-93606D02*
X834140D01*
X833485Y-91564D01*
X832393Y-90398D01*
X830865Y-89815D01*
X829336Y-90106D01*
X828026Y-90981D01*
X827153Y-93023D01*
X826716Y-94773D01*
Y-96523D01*
X827153Y-98273D01*
X828245Y-100023D01*
X829555Y-101189D01*
X831083Y-101481D01*
X832611Y-100898D01*
X834140Y-99148D01*
G01X860843D02*
X862590Y-100606D01*
X864555Y-101481D01*
X866301D01*
X868048Y-100606D01*
X869358Y-99148D01*
X870013Y-97106D01*
X869576Y-95065D01*
X868485Y-93314D01*
X866520Y-92148D01*
X863900Y-91564D01*
X862371Y-90398D01*
X861716Y-88356D01*
X862153Y-86314D01*
X863245Y-84856D01*
X864773Y-83981D01*
X866301D01*
X867830Y-84564D01*
X869140Y-86023D01*
G01X887295Y-101481D02*
X878561D01*
Y-83981D01*
X887295D01*
G01X883801Y-92439D02*
X878561D01*
G01X917928Y-89815D02*
Y-101481D01*
G01Y-85148D02*
X917491Y-84856D01*
Y-84273D01*
X917928Y-83981D01*
X918365Y-84273D01*
Y-84856D01*
X917928Y-85148D01*
G01X928878Y-101481D02*
Y-89815D01*
G01Y-93023D02*
X929533Y-91564D01*
X930625Y-90398D01*
X932153Y-89815D01*
X933681Y-90398D01*
X934773Y-91564D01*
X935428Y-93023D01*
Y-101481D01*
G01Y-93023D02*
X936083Y-91564D01*
X937174Y-90398D01*
X938703Y-89815D01*
X940231Y-90398D01*
X941323Y-91564D01*
X941978Y-93314D01*
Y-101481D01*
G01X948998Y-107314D02*
Y-89815D01*
G01Y-92439D02*
X950090Y-90981D01*
X951181Y-90106D01*
X952928Y-89815D01*
X954456Y-90106D01*
X955985Y-91564D01*
X956640Y-93606D01*
X956858Y-95648D01*
X956640Y-97690D01*
X955985Y-99731D01*
X954674Y-100898D01*
X952928Y-101481D01*
X951400Y-101189D01*
X949871Y-100315D01*
X948998Y-99148D01*
G01X967153Y-93606D02*
X974140D01*
X973485Y-91564D01*
X972393Y-90398D01*
X970865Y-89815D01*
X969336Y-90106D01*
X968026Y-90981D01*
X967153Y-93023D01*
X966716Y-94773D01*
Y-96523D01*
X967153Y-98273D01*
X968245Y-100023D01*
X969555Y-101189D01*
X971083Y-101481D01*
X972611Y-100898D01*
X974140Y-99148D01*
G01X991858Y-83981D02*
Y-101481D01*
G01Y-98857D02*
X990985Y-100315D01*
X989674Y-101189D01*
X988146Y-101481D01*
X986400Y-100898D01*
X985090Y-99440D01*
X984216Y-97690D01*
X983998Y-95648D01*
X984216Y-93606D01*
X985090Y-91856D01*
X986400Y-90398D01*
X988146Y-89815D01*
X989674Y-90106D01*
X990766Y-90690D01*
X991858Y-91856D01*
G01X1009358Y-101481D02*
Y-89815D01*
G01Y-91856D02*
X1008485Y-90690D01*
X1007174Y-90106D01*
X1005646Y-89815D01*
X1004118Y-90398D01*
X1002808Y-91564D01*
X1001934Y-93314D01*
X1001498Y-95648D01*
X1001934Y-97981D01*
X1002808Y-99731D01*
X1004118Y-100898D01*
X1005646Y-101481D01*
X1007174Y-101189D01*
X1008485Y-100315D01*
X1009358Y-99148D01*
G01X1019216Y-101481D02*
Y-89815D01*
G01Y-92731D02*
X1020090Y-91273D01*
X1021400Y-90106D01*
X1023146Y-89815D01*
X1024674Y-90106D01*
X1025985Y-91273D01*
X1026640Y-93314D01*
Y-101481D01*
G01X1043921Y-91273D02*
X1042393Y-90106D01*
X1041083Y-89815D01*
X1039336Y-90398D01*
X1038026Y-91564D01*
X1037153Y-93606D01*
X1036934Y-95648D01*
X1037153Y-97690D01*
X1038026Y-99440D01*
X1039336Y-100898D01*
X1041083Y-101481D01*
X1042611Y-100898D01*
X1043921Y-99731D01*
G01X1054653Y-93606D02*
X1061640D01*
X1060985Y-91564D01*
X1059893Y-90398D01*
X1058365Y-89815D01*
X1056836Y-90106D01*
X1055526Y-90981D01*
X1054653Y-93023D01*
X1054216Y-94773D01*
Y-96523D01*
X1054653Y-98273D01*
X1055745Y-100023D01*
X1057055Y-101189D01*
X1058583Y-101481D01*
X1060111Y-100898D01*
X1061640Y-99148D01*
G01X1092928Y-83981D02*
Y-101481D01*
G01X1089871Y-89815D02*
X1095985D01*
G01X1107371Y-101481D02*
Y-89815D01*
G01Y-92148D02*
X1108463Y-90981D01*
X1109555Y-90106D01*
X1111083Y-89815D01*
X1112174Y-90106D01*
X1113485Y-90981D01*
G01X1131858Y-101481D02*
Y-89815D01*
G01Y-91856D02*
X1130985Y-90690D01*
X1129674Y-90106D01*
X1128146Y-89815D01*
X1126618Y-90398D01*
X1125308Y-91564D01*
X1124434Y-93314D01*
X1123998Y-95648D01*
X1124434Y-97981D01*
X1125308Y-99731D01*
X1126618Y-100898D01*
X1128146Y-101481D01*
X1129674Y-101189D01*
X1130985Y-100315D01*
X1131858Y-99148D01*
G01X1148921Y-91273D02*
X1147393Y-90106D01*
X1146083Y-89815D01*
X1144336Y-90398D01*
X1143026Y-91564D01*
X1142153Y-93606D01*
X1141934Y-95648D01*
X1142153Y-97690D01*
X1143026Y-99440D01*
X1144336Y-100898D01*
X1146083Y-101481D01*
X1147611Y-100898D01*
X1148921Y-99731D01*
G01X1159653Y-93606D02*
X1166640D01*
X1165985Y-91564D01*
X1164893Y-90398D01*
X1163365Y-89815D01*
X1161836Y-90106D01*
X1160526Y-90981D01*
X1159653Y-93023D01*
X1159216Y-94773D01*
Y-96523D01*
X1159653Y-98273D01*
X1160745Y-100023D01*
X1162055Y-101189D01*
X1163583Y-101481D01*
X1165111Y-100898D01*
X1166640Y-99148D01*
G01X1177153Y-99440D02*
X1178245Y-100606D01*
X1179773Y-101481D01*
X1181083D01*
X1182393Y-100898D01*
X1183266Y-100023D01*
X1183703Y-98857D01*
X1183485Y-97106D01*
X1182611Y-96231D01*
X1178681Y-94481D01*
X1177808Y-92439D01*
X1178245Y-90981D01*
X1179118Y-90106D01*
X1180428Y-89815D01*
X1181738Y-90106D01*
X1183048Y-90981D01*
G01X1215428Y-89815D02*
Y-101481D01*
G01Y-85148D02*
X1214991Y-84856D01*
Y-84273D01*
X1215428Y-83981D01*
X1215865Y-84273D01*
Y-84856D01*
X1215428Y-85148D01*
G01X1229216Y-101481D02*
Y-89815D01*
G01Y-92731D02*
X1230090Y-91273D01*
X1231400Y-90106D01*
X1233146Y-89815D01*
X1234674Y-90106D01*
X1235985Y-91273D01*
X1236640Y-93314D01*
Y-101481D01*
G01X1267928D02*
Y-83981D01*
G01X1289358Y-101481D02*
Y-89815D01*
G01Y-91856D02*
X1288485Y-90690D01*
X1287174Y-90106D01*
X1285646Y-89815D01*
X1284118Y-90398D01*
X1282808Y-91564D01*
X1281934Y-93314D01*
X1281498Y-95648D01*
X1281934Y-97981D01*
X1282808Y-99731D01*
X1284118Y-100898D01*
X1285646Y-101481D01*
X1287174Y-101189D01*
X1288485Y-100315D01*
X1289358Y-99148D01*
G01X1298343Y-106731D02*
X1299653Y-107314D01*
X1301400Y-106731D01*
X1302491Y-105565D01*
X1303365Y-104106D01*
X1304674Y-99440D01*
X1307513Y-89815D01*
G01X1300526D02*
X1304674Y-99440D01*
G01X1317153Y-93606D02*
X1324140D01*
X1323485Y-91564D01*
X1322393Y-90398D01*
X1320865Y-89815D01*
X1319336Y-90106D01*
X1318026Y-90981D01*
X1317153Y-93023D01*
X1316716Y-94773D01*
Y-96523D01*
X1317153Y-98273D01*
X1318245Y-100023D01*
X1319555Y-101189D01*
X1321083Y-101481D01*
X1322611Y-100898D01*
X1324140Y-99148D01*
G01X1334871Y-101481D02*
Y-89815D01*
G01Y-92148D02*
X1335963Y-90981D01*
X1337055Y-90106D01*
X1338583Y-89815D01*
X1339674Y-90106D01*
X1340985Y-90981D01*
G01X1368561Y-83981D02*
Y-101481D01*
X1377295D01*
G01X1390428D02*
Y-83981D01*
X1387808Y-87481D01*
G01Y-101481D02*
X1393048D01*
G01X1407928Y-102064D02*
X1407491Y-101773D01*
Y-101189D01*
X1407928Y-100898D01*
X1408365Y-101189D01*
Y-101773D01*
X1407928Y-102064D01*
G01X1481935Y875371D02*
X1483682Y873913D01*
X1485647Y873038D01*
X1487393D01*
X1489140Y873913D01*
X1490450Y875371D01*
X1491105Y877413D01*
X1490668Y879454D01*
X1489577Y881205D01*
X1487612Y882371D01*
X1484992Y882955D01*
X1483463Y884121D01*
X1482808Y886163D01*
X1483245Y888205D01*
X1484337Y889663D01*
X1485865Y890538D01*
X1487393D01*
X1488922Y889955D01*
X1490232Y888496D01*
G01X1508387Y873038D02*
X1499653D01*
Y890538D01*
X1508387D01*
G01X1504893Y882080D02*
X1499653D01*
G01X1536400Y890538D02*
X1541640D01*
G01X1539020D02*
Y873038D01*
G01X1536400D02*
X1541640D01*
G01X1550843D02*
Y890538D01*
X1556520Y875955D01*
X1562197Y890538D01*
Y873038D01*
G01X1569653D02*
Y890538D01*
X1574893D01*
X1576640Y889663D01*
X1577950Y887621D01*
X1578387Y885288D01*
X1577950Y882955D01*
X1576858Y881205D01*
X1574893Y880329D01*
X1569653D01*
G01X1595887Y873038D02*
X1587153D01*
Y890538D01*
X1595887D01*
G01X1592393Y882080D02*
X1587153D01*
G01X1604217Y873038D02*
Y890538D01*
X1608583D01*
X1610330Y889663D01*
X1611640Y888496D01*
X1612732Y886747D01*
X1613605Y884704D01*
X1613823Y881788D01*
X1613605Y878871D01*
X1612732Y876829D01*
X1611640Y875079D01*
X1610330Y873913D01*
X1608583Y873038D01*
X1604217D01*
G01X1621061D02*
X1626520Y890538D01*
X1631979Y873038D01*
G01X1630013Y879163D02*
X1623026D01*
G01X1638998Y873038D02*
Y890538D01*
X1649042Y873038D01*
Y890538D01*
G01X1666323Y889079D02*
X1665013Y889955D01*
X1663485Y890538D01*
X1661738D01*
X1659773Y889663D01*
X1658245Y888205D01*
X1657153Y886454D01*
X1656280Y883538D01*
X1656061Y880913D01*
X1656498Y878288D01*
X1657153Y876538D01*
X1658463Y874788D01*
X1659992Y873621D01*
X1661520Y873038D01*
X1663048D01*
X1664577Y873621D01*
X1665887Y874496D01*
X1666979Y875662D01*
G01X1683387Y873038D02*
X1674653D01*
Y890538D01*
X1683387D01*
G01X1679893Y882080D02*
X1674653D01*
G01X1714020Y890538D02*
Y873038D01*
G01X1708998Y890538D02*
X1719042D01*
G01X1726061Y873038D02*
X1731520Y890538D01*
X1736979Y873038D01*
G01X1735013Y879163D02*
X1728026D01*
G01X1750766Y882371D02*
X1751640Y883246D01*
X1752295Y884704D01*
X1752732Y886747D01*
X1752295Y888496D01*
X1751422Y889663D01*
X1749893Y890538D01*
X1743998D01*
Y873038D01*
X1751203D01*
X1752732Y874204D01*
X1753605Y875955D01*
X1754042Y877996D01*
X1753605Y880038D01*
X1752295Y881788D01*
X1750766Y882371D01*
X1743998D01*
G01X1762153Y890538D02*
Y873038D01*
X1770887D01*
G01X1788387D02*
X1779653D01*
Y890538D01*
X1788387D01*
G01X1784893Y882080D02*
X1779653D01*
G01X1801520Y872455D02*
X1801083Y872746D01*
Y873330D01*
X1801520Y873621D01*
X1801957Y873330D01*
Y872746D01*
X1801520Y872455D01*
G01Y880329D02*
X1801083Y880621D01*
Y881205D01*
X1801520Y881496D01*
X1801957Y881205D01*
Y880621D01*
X1801520Y880329D01*
G01X1832153Y890538D02*
Y873038D01*
X1840887D01*
G01X1854020D02*
Y890538D01*
X1851400Y887038D01*
G01Y873038D02*
X1856640D01*
G01X1503600Y855888D02*
X1508840D01*
G01X1506220D02*
Y838388D01*
G01X1503600D02*
X1508840D01*
G01X1518043D02*
Y855888D01*
X1523720Y841305D01*
X1529397Y855888D01*
Y838388D01*
G01X1536853D02*
Y855888D01*
X1542093D01*
X1543840Y855013D01*
X1545150Y852971D01*
X1545587Y850638D01*
X1545150Y848305D01*
X1544058Y846555D01*
X1542093Y845679D01*
X1536853D01*
G01X1557628Y832555D02*
X1555445Y835471D01*
X1554353Y838388D01*
Y850054D01*
X1555445Y852971D01*
X1557628Y855888D01*
G01X1576220Y838388D02*
X1574473Y838680D01*
X1572945Y839846D01*
X1571635Y841596D01*
X1570761Y843638D01*
X1570325Y845971D01*
Y848305D01*
X1570761Y850638D01*
X1571635Y852680D01*
X1572945Y854429D01*
X1574473Y855596D01*
X1576220Y855888D01*
X1577966Y855596D01*
X1579495Y854429D01*
X1580805Y852680D01*
X1581679Y850638D01*
X1582115Y848305D01*
Y845971D01*
X1581679Y843638D01*
X1580805Y841596D01*
X1579495Y839846D01*
X1577966Y838680D01*
X1576220Y838388D01*
G01X1590008D02*
Y855888D01*
G01Y847430D02*
X1591100Y848888D01*
X1592192Y849763D01*
X1593938Y850054D01*
X1595248Y849763D01*
X1596777Y848596D01*
X1597432Y846846D01*
Y838388D01*
G01X1604670D02*
Y850054D01*
G01Y846846D02*
X1605325Y848305D01*
X1606417Y849471D01*
X1607945Y850054D01*
X1609473Y849471D01*
X1610565Y848305D01*
X1611220Y846846D01*
Y838388D01*
G01Y846846D02*
X1611875Y848305D01*
X1612966Y849471D01*
X1614495Y850054D01*
X1616023Y849471D01*
X1617115Y848305D01*
X1617770Y846555D01*
Y838388D01*
G01X1629812Y832555D02*
X1631995Y835471D01*
X1633087Y838388D01*
Y850054D01*
X1631995Y852971D01*
X1629812Y855888D01*
G01X1536417Y806362D02*
X1537726Y804904D01*
X1539255Y804030D01*
X1541220Y803738D01*
X1543185Y804321D01*
X1544713Y805488D01*
X1545805Y807529D01*
X1546023Y809863D01*
X1545587Y812196D01*
X1544495Y813655D01*
X1542966Y814821D01*
X1541438Y815113D01*
X1539910Y814821D01*
X1537945Y813655D01*
X1538600Y821238D01*
X1544495D01*
G01X1558720D02*
X1556973Y820655D01*
X1555663Y819196D01*
X1554790Y817447D01*
X1554135Y815113D01*
X1553917Y812488D01*
X1554135Y809863D01*
X1554790Y807529D01*
X1555663Y805779D01*
X1556973Y804321D01*
X1558720Y803738D01*
X1560466Y804321D01*
X1561777Y805779D01*
X1562650Y807529D01*
X1563305Y809863D01*
X1563523Y812488D01*
X1563305Y815113D01*
X1562650Y817447D01*
X1561777Y819196D01*
X1560466Y820655D01*
X1558720Y821238D01*
G01X1576220Y803155D02*
X1575783Y803446D01*
Y804030D01*
X1576220Y804321D01*
X1576657Y804030D01*
Y803446D01*
X1576220Y803155D01*
G01X1593720Y821238D02*
X1591973Y820655D01*
X1590663Y819196D01*
X1589790Y817447D01*
X1589135Y815113D01*
X1588917Y812488D01*
X1589135Y809863D01*
X1589790Y807529D01*
X1590663Y805779D01*
X1591973Y804321D01*
X1593720Y803738D01*
X1595466Y804321D01*
X1596777Y805779D01*
X1597650Y807529D01*
X1598305Y809863D01*
X1598523Y812488D01*
X1598305Y815113D01*
X1597650Y817447D01*
X1596777Y819196D01*
X1595466Y820655D01*
X1593720Y821238D01*
G01X1674670Y855888D02*
X1677726Y838388D01*
X1681220Y855888D01*
X1684713Y838388D01*
X1687770Y855888D01*
G01X1696100D02*
X1701340D01*
G01X1698720D02*
Y838388D01*
G01X1696100D02*
X1701340D01*
G01X1711417D02*
Y855888D01*
X1715783D01*
X1717530Y855013D01*
X1718840Y853846D01*
X1719932Y852097D01*
X1720805Y850054D01*
X1721023Y847138D01*
X1720805Y844221D01*
X1719932Y842179D01*
X1718840Y840429D01*
X1717530Y839263D01*
X1715783Y838388D01*
X1711417D01*
G01X1733720Y855888D02*
Y838388D01*
G01X1728698Y855888D02*
X1738742D01*
G01X1746635Y838388D02*
Y855888D01*
G01X1755805D02*
Y838388D01*
G01Y847138D02*
X1746635D01*
G01X1767628Y832555D02*
X1765445Y835471D01*
X1764353Y838388D01*
Y850054D01*
X1765445Y852971D01*
X1767628Y855888D01*
G01X1779670Y838388D02*
Y850054D01*
G01Y846846D02*
X1780325Y848305D01*
X1781417Y849471D01*
X1782945Y850054D01*
X1784473Y849471D01*
X1785565Y848305D01*
X1786220Y846846D01*
Y838388D01*
G01Y846846D02*
X1786875Y848305D01*
X1787966Y849471D01*
X1789495Y850054D01*
X1791023Y849471D01*
X1792115Y848305D01*
X1792770Y846555D01*
Y838388D01*
G01X1803720Y850054D02*
Y838388D01*
G01Y854721D02*
X1803283Y855013D01*
Y855596D01*
X1803720Y855888D01*
X1804157Y855596D01*
Y855013D01*
X1803720Y854721D01*
G01X1821220Y838388D02*
Y855888D01*
G01X1835445Y840429D02*
X1836537Y839263D01*
X1838065Y838388D01*
X1839375D01*
X1840685Y838971D01*
X1841558Y839846D01*
X1841995Y841012D01*
X1841777Y842763D01*
X1840903Y843638D01*
X1836973Y845388D01*
X1836100Y847430D01*
X1836537Y848888D01*
X1837410Y849763D01*
X1838720Y850054D01*
X1840030Y849763D01*
X1841340Y848888D01*
G01X1857312Y832555D02*
X1859495Y835471D01*
X1860587Y838388D01*
Y850054D01*
X1859495Y852971D01*
X1857312Y855888D01*
G01X1745090Y803738D02*
Y821238D01*
X1737011Y808696D01*
X1747929D01*
G01X1759970Y803155D02*
X1759533Y803446D01*
Y804030D01*
X1759970Y804321D01*
X1760407Y804030D01*
Y803446D01*
X1759970Y803155D01*
G01X1777033Y803738D02*
X1777470Y807529D01*
X1778125Y810738D01*
X1778998Y813655D01*
X1780090Y816863D01*
X1781837Y821238D01*
X1773103D01*
G01X1790167Y806362D02*
X1791476Y804904D01*
X1793005Y804030D01*
X1794970Y803738D01*
X1796935Y804321D01*
X1798463Y805488D01*
X1799555Y807529D01*
X1799773Y809863D01*
X1799337Y812196D01*
X1798245Y813655D01*
X1796716Y814821D01*
X1795188Y815113D01*
X1793660Y814821D01*
X1791695Y813655D01*
X1792350Y821238D01*
X1798245D01*
G01X1908720Y855888D02*
Y838388D01*
G01X1903698Y855888D02*
X1913742D01*
G01X1926220Y838388D02*
Y846263D01*
X1921853Y855888D01*
G01X1930587D02*
X1926220Y846263D01*
G01X1939353Y838388D02*
Y855888D01*
X1944593D01*
X1946340Y855013D01*
X1947650Y852971D01*
X1948087Y850638D01*
X1947650Y848305D01*
X1946558Y846555D01*
X1944593Y845679D01*
X1939353D01*
G01X1965587Y838388D02*
X1956853D01*
Y855888D01*
X1965587D01*
G01X1962093Y847430D02*
X1956853D01*
G01X1921635Y806071D02*
X1923382Y804613D01*
X1925347Y803738D01*
X1927093D01*
X1928840Y804613D01*
X1930150Y806071D01*
X1930805Y808113D01*
X1930368Y810154D01*
X1929277Y811905D01*
X1927312Y813071D01*
X1924692Y813655D01*
X1923163Y814821D01*
X1922508Y816863D01*
X1922945Y818905D01*
X1924037Y820363D01*
X1925565Y821238D01*
X1927093D01*
X1928622Y820655D01*
X1929932Y819196D01*
G01X1948087Y803738D02*
X1939353D01*
Y821238D01*
X1948087D01*
G01X1944593Y812780D02*
X1939353D01*
G01X2009353Y838388D02*
Y855888D01*
X2014812D01*
X2016558Y855013D01*
X2017650Y853846D01*
X2018087Y851513D01*
X2017650Y849179D01*
X2016340Y847721D01*
X2014812Y846846D01*
X2009353D01*
G01X2014812D02*
X2018087Y838388D01*
G01X2027945Y846263D02*
X2034932D01*
X2034277Y848305D01*
X2033185Y849471D01*
X2031657Y850054D01*
X2030128Y849763D01*
X2028818Y848888D01*
X2027945Y846846D01*
X2027508Y845096D01*
Y843346D01*
X2027945Y841596D01*
X2029037Y839846D01*
X2030347Y838680D01*
X2031875Y838388D01*
X2033403Y838971D01*
X2034932Y840721D01*
G01X2047410Y838388D02*
Y853263D01*
X2047847Y854721D01*
X2048720Y855596D01*
X2050030Y855888D01*
X2051340Y855305D01*
X2051995Y853846D01*
G01X2049375Y848888D02*
X2045008D01*
G01X2066220Y837805D02*
X2065783Y838096D01*
Y838680D01*
X2066220Y838971D01*
X2066657Y838680D01*
Y838096D01*
X2066220Y837805D01*
G01X2096853Y838388D02*
Y855888D01*
X2102093D01*
X2103840Y855013D01*
X2105150Y852971D01*
X2105587Y850638D01*
X2105150Y848305D01*
X2104058Y846555D01*
X2102093Y845679D01*
X2096853D01*
G01X2118720Y838388D02*
Y855888D01*
G01X2140150Y838388D02*
Y850054D01*
G01Y848013D02*
X2139277Y849179D01*
X2137966Y849763D01*
X2136438Y850054D01*
X2134910Y849471D01*
X2133600Y848305D01*
X2132726Y846555D01*
X2132290Y844221D01*
X2132726Y841888D01*
X2133600Y840138D01*
X2134910Y838971D01*
X2136438Y838388D01*
X2137966Y838680D01*
X2139277Y839554D01*
X2140150Y840721D01*
G01X2150008Y838388D02*
Y850054D01*
G01Y847138D02*
X2150882Y848596D01*
X2152192Y849763D01*
X2153938Y850054D01*
X2155466Y849763D01*
X2156777Y848596D01*
X2157432Y846555D01*
Y838388D01*
G01X2167945Y846263D02*
X2174932D01*
X2174277Y848305D01*
X2173185Y849471D01*
X2171657Y850054D01*
X2170128Y849763D01*
X2168818Y848888D01*
X2167945Y846846D01*
X2167508Y845096D01*
Y843346D01*
X2167945Y841596D01*
X2169037Y839846D01*
X2170347Y838680D01*
X2171875Y838388D01*
X2173403Y838971D01*
X2174932Y840721D01*
G01X2079353Y821238D02*
Y803738D01*
X2088087D01*
G01X2097072Y818321D02*
X2098382Y820071D01*
X2099910Y820946D01*
X2101657Y821238D01*
X2103840Y820655D01*
X2105368Y819196D01*
X2105805Y817447D01*
X2105587Y815696D01*
X2104713Y814238D01*
X2100347Y811321D01*
X2098382Y809280D01*
X2097072Y806362D01*
X2096635Y803738D01*
X2105805D01*
G01X2289020Y815404D02*
Y803738D01*
G01Y820071D02*
X2288583Y820363D01*
Y820946D01*
X2289020Y821238D01*
X2289457Y820946D01*
Y820363D01*
X2289020Y820071D01*
G01X2303245Y805779D02*
X2304337Y804613D01*
X2305865Y803738D01*
X2307175D01*
X2308485Y804321D01*
X2309358Y805196D01*
X2309795Y806362D01*
X2309577Y808113D01*
X2308703Y808988D01*
X2304773Y810738D01*
X2303900Y812780D01*
X2304337Y814238D01*
X2305210Y815113D01*
X2306520Y815404D01*
X2307830Y815113D01*
X2309140Y814238D01*
G01X2336498Y803738D02*
Y821238D01*
X2346542Y803738D01*
Y821238D01*
G01X2359020Y803738D02*
X2357273Y804030D01*
X2355745Y805196D01*
X2354435Y806946D01*
X2353561Y808988D01*
X2353125Y811321D01*
Y813655D01*
X2353561Y815988D01*
X2354435Y818030D01*
X2355745Y819779D01*
X2357273Y820946D01*
X2359020Y821238D01*
X2360766Y820946D01*
X2362295Y819779D01*
X2363605Y818030D01*
X2364479Y815988D01*
X2364915Y813655D01*
Y811321D01*
X2364479Y808988D01*
X2363605Y806946D01*
X2362295Y805196D01*
X2360766Y804030D01*
X2359020Y803738D01*
G01X2376520Y821238D02*
Y803738D01*
G01X2371498Y821238D02*
X2381542D01*
G01X2407808Y815404D02*
Y807238D01*
X2408682Y805196D01*
X2409992Y804030D01*
X2411520Y803738D01*
X2413048Y804030D01*
X2414358Y805196D01*
X2415232Y807238D01*
G01Y803738D02*
Y815404D01*
G01X2425745Y805779D02*
X2426837Y804613D01*
X2428365Y803738D01*
X2429675D01*
X2430985Y804321D01*
X2431858Y805196D01*
X2432295Y806362D01*
X2432077Y808113D01*
X2431203Y808988D01*
X2427273Y810738D01*
X2426400Y812780D01*
X2426837Y814238D01*
X2427710Y815113D01*
X2429020Y815404D01*
X2430330Y815113D01*
X2431640Y814238D01*
G01X2443245Y811613D02*
X2450232D01*
X2449577Y813655D01*
X2448485Y814821D01*
X2446957Y815404D01*
X2445428Y815113D01*
X2444118Y814238D01*
X2443245Y812196D01*
X2442808Y810446D01*
Y808696D01*
X2443245Y806946D01*
X2444337Y805196D01*
X2445647Y804030D01*
X2447175Y803738D01*
X2448703Y804321D01*
X2450232Y806071D01*
G01X2467950Y821238D02*
Y803738D01*
G01Y806362D02*
X2467077Y804904D01*
X2465766Y804030D01*
X2464238Y803738D01*
X2462492Y804321D01*
X2461182Y805779D01*
X2460308Y807529D01*
X2460090Y809571D01*
X2460308Y811613D01*
X2461182Y813363D01*
X2462492Y814821D01*
X2464238Y815404D01*
X2465766Y815113D01*
X2466858Y814529D01*
X2467950Y813363D01*
G01X2214217Y837805D02*
X2223823Y850638D01*
G01X2219020Y852971D02*
Y835471D01*
G01X2223823Y837805D02*
X2214217Y850638D01*
G01X2212470Y844221D02*
X2225570D01*
G01X2251182D02*
X2256858D01*
G01X2284217Y838388D02*
Y855888D01*
X2288583D01*
X2290330Y855013D01*
X2291640Y853846D01*
X2292732Y852097D01*
X2293605Y850054D01*
X2293823Y847138D01*
X2293605Y844221D01*
X2292732Y842179D01*
X2291640Y840429D01*
X2290330Y839263D01*
X2288583Y838388D01*
X2284217D01*
G01X2303245Y846263D02*
X2310232D01*
X2309577Y848305D01*
X2308485Y849471D01*
X2306957Y850054D01*
X2305428Y849763D01*
X2304118Y848888D01*
X2303245Y846846D01*
X2302808Y845096D01*
Y843346D01*
X2303245Y841596D01*
X2304337Y839846D01*
X2305647Y838680D01*
X2307175Y838388D01*
X2308703Y838971D01*
X2310232Y840721D01*
G01X2320308Y838388D02*
Y850054D01*
G01Y847138D02*
X2321182Y848596D01*
X2322492Y849763D01*
X2324238Y850054D01*
X2325766Y849763D01*
X2327077Y848596D01*
X2327732Y846555D01*
Y838388D01*
G01X2341520D02*
X2340210Y838680D01*
X2338900Y839846D01*
X2338026Y841888D01*
X2337590Y844221D01*
X2338026Y846555D01*
X2338900Y848596D01*
X2340210Y849763D01*
X2341520Y850054D01*
X2342830Y849763D01*
X2344140Y848596D01*
X2345013Y846555D01*
X2345232Y844221D01*
X2345013Y841888D01*
X2344140Y839846D01*
X2342830Y838680D01*
X2341520Y838388D01*
G01X2359020Y855888D02*
Y838388D01*
G01X2355963Y850054D02*
X2362077D01*
G01X2373245Y846263D02*
X2380232D01*
X2379577Y848305D01*
X2378485Y849471D01*
X2376957Y850054D01*
X2375428Y849763D01*
X2374118Y848888D01*
X2373245Y846846D01*
X2372808Y845096D01*
Y843346D01*
X2373245Y841596D01*
X2374337Y839846D01*
X2375647Y838680D01*
X2377175Y838388D01*
X2378703Y838971D01*
X2380232Y840721D01*
G01X2390745Y840429D02*
X2391837Y839263D01*
X2393365Y838388D01*
X2394675D01*
X2395985Y838971D01*
X2396858Y839846D01*
X2397295Y841012D01*
X2397077Y842763D01*
X2396203Y843638D01*
X2392273Y845388D01*
X2391400Y847430D01*
X2391837Y848888D01*
X2392710Y849763D01*
X2394020Y850054D01*
X2395330Y849763D01*
X2396640Y848888D01*
G01X2429020Y855888D02*
Y838388D01*
G01X2425963Y850054D02*
X2432077D01*
G01X2442808Y838388D02*
Y855888D01*
G01Y847430D02*
X2443900Y848888D01*
X2444992Y849763D01*
X2446738Y850054D01*
X2448048Y849763D01*
X2449577Y848596D01*
X2450232Y846846D01*
Y838388D01*
G01X2467950D02*
Y850054D01*
G01Y848013D02*
X2467077Y849179D01*
X2465766Y849763D01*
X2464238Y850054D01*
X2462710Y849471D01*
X2461400Y848305D01*
X2460526Y846555D01*
X2460090Y844221D01*
X2460526Y841888D01*
X2461400Y840138D01*
X2462710Y838971D01*
X2464238Y838388D01*
X2465766Y838680D01*
X2467077Y839554D01*
X2467950Y840721D01*
G01X2481520Y855888D02*
Y838388D01*
G01X2478463Y850054D02*
X2484577D01*
G01X2516520Y855888D02*
Y838388D01*
G01X2513463Y850054D02*
X2519577D01*
G01X2530308Y838388D02*
Y855888D01*
G01Y847430D02*
X2531400Y848888D01*
X2532492Y849763D01*
X2534238Y850054D01*
X2535548Y849763D01*
X2537077Y848596D01*
X2537732Y846846D01*
Y838388D01*
G01X2551520Y850054D02*
Y838388D01*
G01Y854721D02*
X2551083Y855013D01*
Y855596D01*
X2551520Y855888D01*
X2551957Y855596D01*
Y855013D01*
X2551520Y854721D01*
G01X2565745Y840429D02*
X2566837Y839263D01*
X2568365Y838388D01*
X2569675D01*
X2570985Y838971D01*
X2571858Y839846D01*
X2572295Y841012D01*
X2572077Y842763D01*
X2571203Y843638D01*
X2567273Y845388D01*
X2566400Y847430D01*
X2566837Y848888D01*
X2567710Y849763D01*
X2569020Y850054D01*
X2570330Y849763D01*
X2571640Y848888D01*
G01X2601400Y855888D02*
X2606640D01*
G01X2604020D02*
Y838388D01*
G01X2601400D02*
X2606640D01*
G01X2614970D02*
Y850054D01*
G01Y846846D02*
X2615625Y848305D01*
X2616717Y849471D01*
X2618245Y850054D01*
X2619773Y849471D01*
X2620865Y848305D01*
X2621520Y846846D01*
Y838388D01*
G01Y846846D02*
X2622175Y848305D01*
X2623266Y849471D01*
X2624795Y850054D01*
X2626323Y849471D01*
X2627415Y848305D01*
X2628070Y846555D01*
Y838388D01*
G01X2635090Y832555D02*
Y850054D01*
G01Y847430D02*
X2636182Y848888D01*
X2637273Y849763D01*
X2639020Y850054D01*
X2640548Y849763D01*
X2642077Y848305D01*
X2642732Y846263D01*
X2642950Y844221D01*
X2642732Y842179D01*
X2642077Y840138D01*
X2640766Y838971D01*
X2639020Y838388D01*
X2637492Y838680D01*
X2635963Y839554D01*
X2635090Y840721D01*
G01X2653245Y846263D02*
X2660232D01*
X2659577Y848305D01*
X2658485Y849471D01*
X2656957Y850054D01*
X2655428Y849763D01*
X2654118Y848888D01*
X2653245Y846846D01*
X2652808Y845096D01*
Y843346D01*
X2653245Y841596D01*
X2654337Y839846D01*
X2655647Y838680D01*
X2657175Y838388D01*
X2658703Y838971D01*
X2660232Y840721D01*
G01X2677950Y855888D02*
Y838388D01*
G01Y841012D02*
X2677077Y839554D01*
X2675766Y838680D01*
X2674238Y838388D01*
X2672492Y838971D01*
X2671182Y840429D01*
X2670308Y842179D01*
X2670090Y844221D01*
X2670308Y846263D01*
X2671182Y848013D01*
X2672492Y849471D01*
X2674238Y850054D01*
X2675766Y849763D01*
X2676858Y849179D01*
X2677950Y848013D01*
G01X2695450Y838388D02*
Y850054D01*
G01Y848013D02*
X2694577Y849179D01*
X2693266Y849763D01*
X2691738Y850054D01*
X2690210Y849471D01*
X2688900Y848305D01*
X2688026Y846555D01*
X2687590Y844221D01*
X2688026Y841888D01*
X2688900Y840138D01*
X2690210Y838971D01*
X2691738Y838388D01*
X2693266Y838680D01*
X2694577Y839554D01*
X2695450Y840721D01*
G01X2705308Y838388D02*
Y850054D01*
G01Y847138D02*
X2706182Y848596D01*
X2707492Y849763D01*
X2709238Y850054D01*
X2710766Y849763D01*
X2712077Y848596D01*
X2712732Y846555D01*
Y838388D01*
G01X2730013Y848596D02*
X2728485Y849763D01*
X2727175Y850054D01*
X2725428Y849471D01*
X2724118Y848305D01*
X2723245Y846263D01*
X2723026Y844221D01*
X2723245Y842179D01*
X2724118Y840429D01*
X2725428Y838971D01*
X2727175Y838388D01*
X2728703Y838971D01*
X2730013Y840138D01*
G01X2740745Y846263D02*
X2747732D01*
X2747077Y848305D01*
X2745985Y849471D01*
X2744457Y850054D01*
X2742928Y849763D01*
X2741618Y848888D01*
X2740745Y846846D01*
X2740308Y845096D01*
Y843346D01*
X2740745Y841596D01*
X2741837Y839846D01*
X2743147Y838680D01*
X2744675Y838388D01*
X2746203Y838971D01*
X2747732Y840721D01*
G01X1425733Y-51181D02*
X-29385D01*
G01X-33322Y-47244D02*
G03X-29385Y-51181I3937J0D01*
G01X-33322Y-47244D02*
Y893701D01*
G01X-7874Y102402D02*
Y212205D01*
G01Y102402D02*
G03X0Y94528I7874J0D01*
G01Y212205D02*
G03X-7874I-3937J0D01*
G01Y237402D02*
G03X0I3937J-1D01*
G01X-7874D02*
Y406693D01*
G01X0D02*
G03X-7874I-3937J0D01*
G01Y431890D02*
G03X0I3937J0D01*
G01X-7874D02*
Y601181D01*
G01X0D02*
G03X-7874I-3937J0D01*
G01Y626378D02*
Y795669D01*
G01Y626378D02*
G03X0I3937J0D01*
G01Y795669D02*
G03X-7874I-3937J0D01*
G01Y820866D02*
G03X0I3937J0D01*
G01X-7874Y844488D02*
Y820866D01*
G01X-3937Y848425D02*
G03X-7874Y844488I0J-3937D01*
G01X93307Y848425D02*
X-3937D01*
G01X-29385Y897638D02*
G03X-33322Y893701I0J-3937D01*
G01X-29385Y897638D02*
X93307D01*
G01X98425Y94528D02*
X0D01*
G01X1400000Y36220D02*
G03X1398031Y38189I-1969J0D01*
G01X1396654D01*
G02X1394685Y40157I0J1969D01*
G01Y71654D01*
G02X1396654Y73622I1969J-1D01*
G01X1398031D01*
G03X1400000Y75591I0J1969D01*
G01Y836614D01*
G03X1396063Y840551I-3937J0D01*
G01X1368504D01*
G02X1363386Y845669I0J5118D01*
G01Y871654D01*
G03X1361417Y873622I-1969J-1D01*
G01X1358268D01*
G02X1356299Y875591I0J1969D01*
G01Y892521D01*
X1352363Y897638D01*
X1218110D01*
X1214173Y892520D01*
Y875984D01*
G02X1205512I-4331J0D01*
G01Y892520D01*
X1201575Y897638D01*
X1029528D01*
X1025591Y892520D01*
Y875591D01*
G02X1023622Y873622I-1969J0D01*
G01X1020472D01*
G03X1018504Y871654I0J-1968D01*
G01Y845669D01*
G02X1013386Y840551I-5118J0D01*
G01X1008433D01*
G03X988748Y820866I0J-19685D01*
G01Y650669D01*
G02X983748Y645669I-5000J0D01*
G01X926819D01*
G02X921819Y650669I0J5000D01*
G01Y820866D01*
G03X902134Y840551I-19685J0D01*
G01X872441D01*
G02X867323Y845669I0J5118D01*
G01Y871654D01*
G03X865354Y873622I-1969J-1D01*
G01X862205D01*
G02X860236Y875591I0J1969D01*
G01Y892521D01*
X856300Y897638D01*
X722048D01*
X718110Y892519D01*
Y875984D01*
G02X709449I-4331J0D01*
G01Y892520D01*
X705512Y897638D01*
X533465D01*
X529528Y892520D01*
Y875591D01*
G02X527559Y873622I-1969J0D01*
G01X524409D01*
G03X522441Y871654I0J-1968D01*
G01Y845669D01*
G02X517323Y840551I-5118J0D01*
G01X455118D01*
G02X450000Y845669I0J5118D01*
G01Y871654D01*
G03X448031Y873622I-1968J0D01*
G01X444882D01*
G02X442913Y875591I0J1969D01*
G01Y892521D01*
X438977Y897638D01*
X304725D01*
X300787Y892519D01*
Y875984D01*
G02X292126I-4331J0D01*
G01Y892521D01*
X288190Y897638D01*
X116142D01*
X112205Y892520D01*
Y875591D01*
G02X110236Y873622I-1969J0D01*
G01X107087D01*
G03X105118Y871654I0J-1969D01*
G01Y845669D01*
G02X100000Y840551I-5118J0D01*
G01X3937D01*
G03X0Y836614I0J-3937D01*
G01Y110276D01*
G03X7874Y102402I7874J0D01*
G01X196654D01*
G02X204528Y94528I0J-7874D01*
G01Y7874D01*
G03X212402Y0I7874J0D01*
G01X471014D01*
G02X478888Y-7874I0J-7874D01*
G01Y-11811D01*
G03X486762Y-19685I7874J0D01*
G01X1302165D01*
G03X1306102Y-15748I0J3937D01*
G01Y-3937D01*
G02X1310039Y0I3937J0D01*
G01X1396063D01*
G03X1400000Y3937I0J3937D01*
G01Y36220D01*
G01X93307Y848425D02*
G03X97244Y852362I0J3937D01*
G01Y893701D02*
Y852362D01*
G01Y893701D02*
G03X93307Y897638I-3937J0D01*
G01X192717Y94528D02*
X123622D01*
G01Y102402D02*
G03Y94528I0J-3937D01*
G01X98425D02*
G03Y102402I0J3937D01*
G01X196654Y0D02*
G03X204528Y-7874I7874J0D01*
G01X196654Y0D02*
Y29961D01*
G01X204528D02*
G03X196654I-3937J0D01*
G01Y55157D02*
Y90591D01*
G01Y55157D02*
G03X204528I3937J0D01*
G01X196654Y90591D02*
G03X192717Y94528I-3937J0D01*
G01X232077Y-7874D02*
G03Y0I0J3937D01*
G01Y-7874D02*
X204528D01*
G01X434439D02*
X257274D01*
G01Y0D02*
G03Y-7874I0J-3937D01*
G01X365945Y38188D02*
G03X367914Y40156I0J1969D01*
G01X354134D02*
G03X356103Y38188I1969J1D01*
G01D02*
X365945D01*
G01X354134Y71653D02*
Y40156D01*
G01X367914Y71653D02*
G03X365945Y73621I-1969J-1D01*
G01X356103D02*
G03X354134Y71653I0J-1969D01*
G01X365945Y73621D02*
X356103D01*
G01X367914Y40156D02*
Y71653D01*
G01X434439Y-7874D02*
G03Y0I0J3937D01*
G01X471014Y-15748D02*
G03X463140Y-7874I-7874J0D01*
G01D02*
X459636D01*
G01Y0D02*
G03Y-7874I0J-3937D01*
G01X707234Y-27559D02*
X478888D01*
G01X471014Y-19685D02*
G03X478888Y-27559I7874J0D01*
G01X471014Y-19685D02*
Y-15748D01*
G01X870226Y-27559D02*
X732431D01*
G01Y-19685D02*
G03Y-27559I0J-3937D01*
G01X707234D02*
G03Y-19685I0J3937D01*
G01X870226Y-27559D02*
G03Y-19685I1J3937D01*
G01X1072589Y-27559D02*
X895423D01*
G01Y-19685D02*
G03Y-27559I0J-3937D01*
G01X1072589D02*
G03Y-19685I0J3937D01*
G01X1097785D02*
G03Y-27559I1J-3937D01*
G01X1336086Y-8662D02*
X1318701D01*
G03X1314764Y-12599I0J-3937D01*
G01Y-23622D01*
G02X1310827Y-27559I-3937J0D01*
G01X1097785D01*
G01X1336086Y-8662D02*
G03Y-1I0J4330D01*
G01X1361283D02*
G03Y-8662I0J-4330D01*
G01X1407874Y13026D02*
Y-4725D01*
G02X1403937Y-8662I-3937J0D01*
G01X1361283D01*
G01X1403937Y848425D02*
X1375197D01*
G01X1371260Y852362D02*
G03X1375197Y848425I3937J0D01*
G01X1371260Y852362D02*
Y893701D01*
G01X1375197Y897638D02*
G03X1371260Y893701I0J-3937D01*
G01X1375197Y897638D02*
X1425733D01*
G01X1407874Y30709D02*
Y219685D01*
G01X1400000Y30709D02*
G03X1407874I3937J0D01*
G01Y13026D02*
G03X1400000I-3937J-1D01*
G01X1407874Y219685D02*
G03X1400000I-3937J0D01*
G01Y244882D02*
G03X1407874I3937J0D01*
G01Y414173D02*
Y244882D01*
G01Y608661D02*
Y439370D01*
G01X1400000D02*
G03X1407874I3937J0D01*
G01Y414173D02*
G03X1400000I-3937J0D01*
G01X1407874Y608661D02*
G03X1400000I-3937J0D01*
G01Y626378D02*
G03X1407874I3937J0D01*
G01Y795669D02*
Y626378D01*
G01Y795669D02*
G03X1400000I-3937J0D01*
G01Y820866D02*
G03X1407874I3937J0D01*
G01Y844488D02*
Y820866D01*
G01Y844488D02*
G03X1403937Y848425I-3937J0D01*
G01X1429670Y893701D02*
Y-47244D01*
G01X1425733Y-51181D02*
G03X1429670Y-47244I0J3937D01*
G01Y893701D02*
G03X1425733Y897638I-3937J0D01*
G54D12*
G01X11700Y198650D02*
Y139700D01*
G01D02*
X31977Y119423D01*
G01Y126614D02*
X29486D01*
G01D02*
X13500Y142600D01*
G01D02*
Y197700D01*
G01X23100Y210050D02*
X11700Y198650D01*
G01X13500Y197700D02*
X31500Y215700D01*
G01X23100Y216950D02*
Y210050D01*
G01Y216950D02*
X27050D01*
G01D02*
X27300Y217200D01*
G01X34894Y233906D02*
X14800Y254000D01*
G01D02*
Y295401D01*
G01D02*
X20637Y301238D01*
G01D02*
X37138D01*
G01X67525Y407163D02*
X27261D01*
G01D02*
X15638Y418786D01*
G01X17063Y419377D02*
X27478Y408962D01*
G01D02*
X33468D01*
G01X15638Y418786D02*
Y491138D01*
G01X17063Y465983D02*
Y419377D01*
G01X23720Y472640D02*
X17063Y465983D01*
G01X15638Y491138D02*
X48700Y524200D01*
G01X29300Y539850D02*
Y536800D01*
G01D02*
X30550Y535550D01*
G01X25000Y527062D02*
X24800Y527262D01*
G01D02*
Y540900D01*
G01X18800Y736851D02*
Y711800D01*
G01D02*
X24050Y706550D01*
G01D02*
Y691400D01*
G01X31200Y712650D02*
X25200D01*
G01X25300Y739150D02*
X21099D01*
G01D02*
X18800Y736851D01*
G01X29400Y738500D02*
X28750Y739150D01*
G01D02*
X25300D01*
G01Y742650D02*
X21250D01*
G01X31050D02*
X25300D01*
G01X33300Y720400D02*
X28550D01*
G01X36300Y746900D02*
X28550D01*
G01X31977Y119423D02*
Y116614D01*
G01X31500Y215700D02*
Y216950D01*
G01D02*
X34894Y220344D01*
G01D02*
Y233906D01*
G01X60673Y280483D02*
Y274527D01*
G01D02*
X60872Y274328D01*
G01X53100Y279500D02*
X52600Y280000D01*
G01D02*
Y281653D01*
G01D02*
X54083Y283136D01*
G01Y292979D02*
X49007D01*
G01D02*
X48128Y292100D01*
G01D02*
X46000D01*
G01X47800Y309400D02*
X50168D01*
G01D02*
X50841Y308727D01*
G01D02*
X54083D01*
G01X58700Y308600D02*
X58705Y308605D01*
G01D02*
Y315317D01*
G01X61800Y306900D02*
Y309933D01*
G01D02*
X60673Y311060D01*
G01X37138Y301238D02*
X38800Y302900D01*
G01X45882Y287141D02*
X49751Y291010D01*
G01D02*
X54083D01*
G01X58300Y327450D02*
X58350D01*
G01D02*
X59922Y325878D01*
G01D02*
Y325278D01*
G01D02*
X62900Y322300D01*
G01X62642Y315317D02*
Y322042D01*
G01D02*
X62900Y322300D01*
G01X43262Y330307D02*
Y326338D01*
G01D02*
X45050Y324550D01*
G01D02*
Y321400D01*
G01X52050Y316100D02*
X54083Y314067D01*
G01D02*
Y312664D01*
G01X60673Y311060D02*
Y315317D01*
G01X54200Y347400D02*
Y342455D01*
G01D02*
X60288Y336367D01*
G01D02*
Y329712D01*
G01D02*
X62800Y327200D01*
G01D02*
Y327150D01*
G01X65200Y324800D02*
X62850Y327150D01*
G01D02*
X62800D01*
G01X64277Y354737D02*
X63500Y353960D01*
G01X39866Y364307D02*
Y371366D01*
G01X65965Y360600D02*
X63398Y358033D01*
G01D02*
X59550D01*
G01X49866Y364307D02*
Y366266D01*
G01D02*
X56500Y372900D01*
G01X44866Y364307D02*
Y361141D01*
G01D02*
X46807Y359200D01*
G01D02*
X52086D01*
G01D02*
X53422Y357864D01*
G01D02*
X51213Y355655D01*
G01D02*
Y351665D01*
G01D02*
X52521Y350357D01*
G01X59550Y367033D02*
X59357Y367226D01*
G01D02*
Y373649D01*
G01D02*
X57900Y375106D01*
G01D02*
Y382546D01*
G01X61799Y372607D02*
X65164D01*
G01X62838Y392392D02*
X61435Y393795D01*
G01D02*
X54613D01*
G01D02*
X49866Y389048D01*
G01D02*
Y384307D01*
G01X33468Y408962D02*
X37500Y412994D01*
G01X57900Y382546D02*
X59399Y384045D01*
G01D02*
X64155D01*
G01X35709Y426942D02*
X36651Y426000D01*
G01D02*
X41900D01*
G01X32750Y429000D02*
X33651D01*
G01D02*
X35709Y426942D01*
G01X37500Y412994D02*
Y414000D01*
G01X40500Y478700D02*
Y480750D01*
G01Y471300D02*
Y469300D01*
G01D02*
X43300Y466500D01*
G01D02*
X44000D01*
G01D02*
X43000Y465500D01*
G01D02*
X40750D01*
G01D02*
X40250Y466000D01*
G01X44500Y484000D02*
X44000Y484500D01*
G01D02*
X40750D01*
G01X40500Y480750D02*
X41188Y481438D01*
G01D02*
X43422D01*
G01D02*
X44500Y482516D01*
G01D02*
Y484000D01*
G01X52000D02*
X53000Y483000D01*
G01D02*
X55750D01*
G01X55500Y488800D02*
Y487500D01*
G01D02*
X52000Y484000D01*
G01X60023Y518541D02*
Y511634D01*
G01D02*
X59587Y511198D01*
G01X55261Y510891D02*
X59280D01*
G01D02*
X59587Y511198D01*
G01X52000Y501500D02*
X52500Y502000D01*
G01D02*
X55750D01*
G01X55500Y496200D02*
Y498500D01*
G01D02*
X55062Y498938D01*
G01D02*
X52969D01*
G01D02*
X52000Y499907D01*
G01D02*
Y501500D01*
G01X61870Y515670D02*
Y511698D01*
G01D02*
X67068Y506500D01*
G01X39616Y532255D02*
Y528260D01*
G01D02*
X38418Y527062D01*
G01D02*
X34000D01*
G01X34050Y533500D02*
X38371D01*
G01D02*
X39616Y532255D01*
G01X48700Y524200D02*
Y536590D01*
G01D02*
X64448Y552338D01*
G01X30550Y535550D02*
Y533500D01*
G01X61800Y537000D02*
X62200Y536600D01*
G01D02*
Y531960D01*
G01D02*
X66890Y527270D01*
G01X61128Y519646D02*
X60023Y518541D01*
G01X66494Y556916D02*
X59084D01*
G01D02*
X54112Y561888D01*
G01D02*
Y577112D01*
G01D02*
X59000Y582000D01*
G01X66000Y598250D02*
X57121Y607129D01*
G01D02*
Y632419D01*
G01X59000Y582000D02*
X73750D01*
G01X67508Y608289D02*
X62611D01*
G01X57121Y632419D02*
X62002Y637300D01*
G01D02*
X72300D01*
G01X78200Y646000D02*
X54000D01*
G01D02*
X53000Y645000D01*
G01X71434Y634800D02*
X63300D01*
G01X70000Y624500D02*
X62400D01*
G01X47800Y666400D02*
X50400D01*
G01D02*
X71900Y687900D01*
G01X63300Y697200D02*
Y703400D01*
G01D02*
X66100Y706200D01*
G01X32498Y682487D02*
X33756D01*
G01D02*
X37700Y686431D01*
G01D02*
Y687500D01*
G01D02*
X41150D01*
G01D02*
X43950Y690300D01*
G01X31550Y687525D02*
Y683435D01*
G01D02*
X32498Y682487D01*
G01X61505Y689980D02*
X64974D01*
G01X61505D02*
X59885D01*
G01D02*
X59315Y690550D01*
G01D02*
X57200D01*
G01X51450Y686425D02*
X57175D01*
G01D02*
X57200Y686450D01*
G01D02*
Y690550D01*
G01X42600Y718000D02*
Y713850D01*
G01D02*
X43300Y713150D01*
G01D02*
X38250D01*
G01D02*
X37300Y712200D01*
G01X31200Y712650D02*
X34050D01*
G01D02*
X34500Y712200D01*
G01D02*
X37300D01*
G01X55350Y713000D02*
X55400Y712950D01*
G01D02*
Y708950D01*
G01D02*
X55350Y708900D01*
G01Y713000D02*
X54700Y713650D01*
G01D02*
Y716250D01*
G01X47300Y716795D02*
Y713150D01*
G01X51300D02*
X47300D01*
G01X35300Y738400D02*
X37816Y735884D01*
G01D02*
X44550D01*
G01X35300Y738400D02*
X31050Y742650D01*
G01X42600Y718000D02*
X44700Y720100D01*
G01D02*
X46900D01*
G01D02*
X49379Y722579D01*
G01D02*
Y725150D01*
G01X45400Y756200D02*
X53316Y748284D01*
G01D02*
Y744650D01*
G01X34800Y721900D02*
X33300Y720400D01*
G01X47410Y724850D02*
X37750D01*
G01D02*
X34800Y721900D01*
G01X68400Y719200D02*
X62750Y724850D01*
G01D02*
X61190D01*
G01X55284Y750116D02*
Y744650D01*
G01X47410Y744950D02*
Y748490D01*
G01D02*
X45800Y750100D01*
G01X37800Y745400D02*
X41410Y741790D01*
G01D02*
X44250D01*
G01X37800Y745400D02*
X36300Y746900D01*
G01X59221Y744650D02*
Y751621D01*
G01X64400Y751800D02*
X61190Y748590D01*
G01D02*
Y744950D01*
G01X53700Y717250D02*
Y720728D01*
G01D02*
X55284Y722312D01*
G01D02*
Y725150D01*
G01X54700Y716250D02*
X53700Y717250D01*
G01X57253Y754747D02*
Y744650D01*
G01X48700Y718195D02*
X53316Y722811D01*
G01D02*
Y725150D01*
G01X48700Y718195D02*
X47300Y716795D01*
G01X49379Y744650D02*
Y749221D01*
G01X42900Y763250D02*
Y758700D01*
G01D02*
X45400Y756200D01*
G01X50900Y756000D02*
Y754500D01*
G01D02*
X55284Y750116D01*
G01X50900Y756000D02*
Y760000D01*
G01D02*
X52300Y761400D01*
G01D02*
Y763150D01*
G01D02*
X48050D01*
G01D02*
X47800Y763400D01*
G01D02*
X45100Y766100D01*
G01D02*
Y778800D01*
G01D02*
X48300Y782000D01*
G01D02*
X57600D01*
G01D02*
X60800Y778800D01*
G01D02*
Y766550D01*
G01X45800Y750100D02*
X41300D01*
G01D02*
X35000Y756400D01*
G01Y763350D02*
Y756400D01*
G01X60800Y763050D02*
X61500D01*
G01D02*
X65000Y766550D01*
G01X61300Y756200D02*
Y756700D01*
G01D02*
X56700Y761300D01*
G01D02*
Y763050D01*
G01X59221Y751621D02*
X61300Y753700D01*
G01D02*
Y756200D01*
G01X56700Y763050D02*
X60800D01*
G01X56100Y755900D02*
X57253Y754747D01*
G01X56100Y755900D02*
X54500Y757500D01*
G01D02*
Y764350D01*
G01D02*
X56700Y766550D01*
G01X56650Y770800D02*
Y773450D01*
G01D02*
X58500Y775300D01*
G01X56700Y766550D02*
Y770750D01*
G01D02*
X56650Y770800D01*
G01X39000Y763350D02*
Y757400D01*
G01D02*
X40200Y756200D01*
G01X49379Y749221D02*
X45900Y752700D01*
G01D02*
X43700D01*
G01D02*
X40200Y756200D01*
G01X108224Y144424D02*
X91189Y127389D01*
G01D02*
Y126614D01*
G01X104611Y145611D02*
X95614Y136614D01*
G01D02*
X91189D01*
G01X104050Y135210D02*
X96919Y128079D01*
G01D02*
Y122344D01*
G01D02*
X91189Y116614D01*
G01X84295Y280483D02*
Y272205D01*
G01D02*
X90100Y266400D01*
G01X82327Y280483D02*
Y276473D01*
G01D02*
X82700Y276100D01*
G01D02*
Y267400D01*
G01D02*
X83300Y266800D01*
G01X80358Y274360D02*
Y269188D01*
G01D02*
X76170Y265000D01*
G01D02*
Y262670D01*
G01X80300Y262650D02*
X76190D01*
G01D02*
X76170Y262670D01*
G01X80358Y280483D02*
Y274360D01*
G01X68100Y265300D02*
X69100Y266300D01*
G01D02*
Y272100D01*
G01D02*
X70000Y273000D01*
G01X70516Y280483D02*
Y273516D01*
G01D02*
X70000Y273000D01*
G01X78390Y280483D02*
Y275557D01*
G01D02*
X78120Y275287D01*
G01D02*
Y271920D01*
G01D02*
X75800Y269600D01*
G01X96677Y285294D02*
Y282702D01*
G01D02*
X95557Y281582D01*
G01X96677Y285294D02*
X94913D01*
G01D02*
X94724Y285105D01*
G01D02*
X88917D01*
G01X95700Y293900D02*
X94653Y294947D01*
G01D02*
X88917D01*
G01X98268Y287532D02*
X94776D01*
G01D02*
X94317Y287073D01*
G01D02*
X88917D01*
G01X101243Y288957D02*
X93143D01*
G01D02*
X93058Y289042D01*
G01D02*
X88917D01*
G01Y283136D02*
X92937Y279116D01*
G01D02*
X97212D01*
G01D02*
X97750Y278578D01*
G01X99887Y340825D02*
X97234Y338172D01*
G01D02*
Y335110D01*
G01D02*
X94863Y332739D01*
G01D02*
Y330123D01*
G01D02*
X92275Y327535D01*
G01D02*
Y324043D01*
G01D02*
X86264Y318032D01*
G01D02*
Y315317D01*
G01X98400Y332400D02*
X96288Y330288D01*
G01D02*
Y328657D01*
G01D02*
X93700Y326069D01*
G01D02*
Y323200D01*
G01D02*
X89417Y318917D01*
G01D02*
Y313164D01*
G01D02*
X88917Y312664D01*
G01X91300Y331600D02*
X89300Y329600D01*
G01D02*
Y325100D01*
G01D02*
X82327Y318127D01*
G01D02*
Y315317D01*
G01X91600Y340650D02*
Y331900D01*
G01D02*
X91300Y331600D01*
G01X95670Y340761D02*
Y336570D01*
G01D02*
X94700Y335600D01*
G01D02*
X93438Y334338D01*
G01D02*
Y330714D01*
G01D02*
X90725Y328001D01*
G01D02*
Y324509D01*
G01D02*
X84295Y318079D01*
G01D02*
Y315317D01*
G01X64610D02*
Y318355D01*
G01D02*
X65200Y318945D01*
G01D02*
Y324800D01*
G01X67093Y354737D02*
X64277D01*
G01X96393Y378707D02*
X99760Y375340D01*
G01X65965Y362838D02*
Y360600D01*
G01Y367408D02*
Y362838D01*
G01Y367408D02*
X69832D01*
G01D02*
X70591Y366649D01*
G01X76241Y365075D02*
X74667Y366649D01*
G01D02*
X70591D01*
G01X90093Y365200D02*
Y371207D01*
G01X89150Y360000D02*
X90093Y360943D01*
G01D02*
Y365200D01*
G01X85800Y355000D02*
Y357238D01*
G01D02*
X85700Y357338D01*
G01D02*
Y359950D01*
G01D02*
X85650Y360000D01*
G01X82500Y362890D02*
X83110D01*
G01D02*
X85650Y360350D01*
G01D02*
Y360000D01*
G01X79555Y360727D02*
X81718Y362890D01*
G01D02*
X82500D01*
G01X79792Y371187D02*
Y365126D01*
G01D02*
X79741Y365075D01*
G01D02*
X79200Y364534D01*
G01D02*
Y361082D01*
G01D02*
X79555Y360727D01*
G01X92157Y381707D02*
X83850Y373400D01*
G01D02*
X82005D01*
G01D02*
X79792Y371187D01*
G01X79455Y357174D02*
X84029Y352600D01*
G01D02*
X95774D01*
G01D02*
X99887Y348487D01*
G01X65164Y372607D02*
X65965Y373408D01*
G01X70654Y374310D02*
X76930D01*
G01D02*
X81307Y378687D01*
G01X70654Y374310D02*
X70364Y374600D01*
G01D02*
Y375872D01*
G01D02*
X68736Y377500D01*
G01D02*
X67000D01*
G01D02*
Y374443D01*
G01D02*
X65965Y373408D01*
G01X73488Y413126D02*
X67525Y407163D01*
G01X84400Y406500D02*
X84274Y406374D01*
G01D02*
Y402591D01*
G01X90028Y405615D02*
X88285D01*
G01D02*
X87400Y406500D01*
G01D02*
X84400D01*
G01X84274Y402591D02*
X80859D01*
G01D02*
X80000Y403450D01*
G01X93968Y378707D02*
X96393D01*
G01X90028Y399115D02*
Y394659D01*
G01D02*
X88034Y392665D01*
G01D02*
X84440D01*
G01D02*
Y395740D01*
G01D02*
X84700Y396000D01*
G01X64800Y383400D02*
X66736Y381464D01*
G01D02*
X68365D01*
G01X64155Y384045D02*
X64800Y383400D01*
G01X100200Y384850D02*
X97057Y381707D01*
G01D02*
X92157D01*
G01X98200Y402563D02*
X95148Y405615D01*
G01X81307Y378687D02*
X83667D01*
G01X102373Y413126D02*
X73488D01*
G01X97099Y477241D02*
X100911D01*
G01X92500Y469750D02*
Y468600D01*
G01D02*
X93314Y467786D01*
G01D02*
Y466166D01*
G01D02*
Y465406D01*
G01D02*
X94720Y464000D01*
G01D02*
X97900D01*
G01X93599Y477241D02*
X92000Y475642D01*
G01D02*
X88784D01*
G01D02*
X86371Y473229D01*
G01D02*
Y464148D01*
G01D02*
X93149Y457370D01*
G01D02*
Y456451D01*
G01D02*
X100500Y449100D01*
G01X89500Y466600D02*
Y464762D01*
G01D02*
X92362Y461900D01*
G01D02*
X93900D01*
G01D02*
X101312Y454488D01*
G01X83894Y508831D02*
X84676Y509613D01*
G01D02*
X88500D01*
G01D02*
X100727D01*
G01X99614Y512037D02*
X86720D01*
G01D02*
X85667Y513090D01*
G01X83894Y504831D02*
X86438Y507375D01*
G01D02*
X89427D01*
G01D02*
X90240Y508188D01*
G01D02*
X94431D01*
G01D02*
X94699Y507920D01*
G01D02*
X101439D01*
G01X66473Y514453D02*
Y511404D01*
G01D02*
X67377Y510500D01*
G01D02*
X70750D01*
G01X95750Y506000D02*
X96080Y505670D01*
G01D02*
X99820D01*
G01X70910Y502219D02*
X70909Y502220D01*
G01D02*
X67019D01*
G01X67068Y506500D02*
X70750D01*
G01X101309Y518825D02*
X97371Y514887D01*
G01D02*
X87902D01*
G01D02*
X85586Y517203D01*
G01D02*
Y518860D01*
G01D02*
X83664Y520782D01*
G01D02*
X81892D01*
G01D02*
X81523Y521151D01*
G01D02*
X81497Y521177D01*
G01D02*
Y523100D01*
G01D02*
X79550Y525047D01*
G01D02*
X72153D01*
G01D02*
X70390Y526810D01*
G01D02*
Y527270D01*
G01X87235Y549285D02*
X84250Y546300D01*
G01X88000Y538500D02*
X89000D01*
G01D02*
X91900Y541400D01*
G01D02*
X96634D01*
G01D02*
X97270Y542036D01*
G01D02*
X97424D01*
G01D02*
X98237Y542849D01*
G01X84250Y534300D02*
X88000Y538050D01*
G01D02*
Y538500D01*
G01X77372Y526885D02*
Y527872D01*
G01D02*
X79162Y529662D01*
G01D02*
Y530705D01*
G01D02*
X80750Y532293D01*
G01D02*
Y534300D01*
G01X85667Y513090D02*
X83019D01*
G01X95750Y538500D02*
X97861Y540611D01*
G01X93100Y543638D02*
X93062Y543600D01*
G01D02*
X91400D01*
G01D02*
X88900Y541100D01*
G01D02*
X87050D01*
G01D02*
X84250Y538300D01*
G01X107530Y544312D02*
X93812D01*
G01D02*
X93138Y543638D01*
G01D02*
X93100D01*
G01X95750Y530500D02*
Y530720D01*
G01D02*
X99476Y534446D01*
G01X75200Y549300D02*
X78200Y546300D01*
G01D02*
X80750D01*
G01X83600Y525700D02*
X81751Y527549D01*
G01D02*
Y528499D01*
G01D02*
X80950Y529300D01*
G01X83600Y525700D02*
X85200D01*
G01D02*
X87011Y523889D01*
G01D02*
Y517794D01*
G01D02*
X88493Y516312D01*
G01D02*
X96612D01*
G01D02*
X101894Y521594D01*
G01X91237Y547047D02*
X92084Y546200D01*
G01D02*
X99600D01*
G01X84250Y542300D02*
X88727Y546777D01*
G01X80750Y538300D02*
X78550Y540500D01*
G01D02*
X72000D01*
G01D02*
X70000Y542500D01*
G01X77700Y522500D02*
X73992D01*
G01D02*
X73787Y522705D01*
G01X71540Y518238D02*
X71870Y517908D01*
G01D02*
Y515620D01*
G01D02*
X70750Y514500D01*
G01X67700Y518500D02*
X71278D01*
G01D02*
X71540Y518238D01*
G01X95750Y534500D02*
X99050Y537800D01*
G01X95750Y526500D02*
Y526606D01*
G01D02*
X100383Y531239D01*
G01X67162Y515142D02*
X66473Y514453D01*
G01X95750Y518500D02*
X101143Y523893D01*
G01X95750Y522500D02*
Y523413D01*
G01D02*
X99829Y527492D01*
G01X74500Y547000D02*
X79200Y542300D01*
G01D02*
X80750D01*
G01X97962Y513462D02*
X87311D01*
G01D02*
X84161Y516612D01*
G01D02*
Y516615D01*
G01D02*
X83686Y517090D01*
G01D02*
X83019D01*
G01X84900Y582250D02*
Y578598D01*
G01D02*
X84226Y577924D01*
G01X98008Y548338D02*
X91962D01*
G01D02*
X91015Y549285D01*
G01D02*
X87235D01*
G01X77500Y554500D02*
X77246Y554754D01*
G01D02*
X73508D01*
G01D02*
X71346Y556916D01*
G01D02*
X66494D01*
G01X64448Y552338D02*
X75338D01*
G01D02*
X77500Y554500D01*
G01X80750D02*
X78938Y556312D01*
G01D02*
X78287D01*
G01D02*
X78261Y556338D01*
G01D02*
X74662D01*
G01D02*
X74000Y557000D01*
G01X73700Y549300D02*
X75200D01*
G01X88727Y547047D02*
X91237D01*
G01X88727Y546777D02*
Y547047D01*
G01X96537Y555253D02*
X97197Y554593D01*
G01D02*
X100742D01*
G01X96537Y555253D02*
X96020Y555770D01*
G01D02*
X86924D01*
G01D02*
X85770Y556924D01*
G01D02*
Y556980D01*
G01D02*
X84250Y558500D01*
G01X100597Y550688D02*
X95512D01*
G01D02*
X95000Y551200D01*
G01D02*
X93400D01*
G01D02*
X92940Y550740D01*
G01D02*
X86640D01*
G01D02*
X86300Y550400D01*
G01D02*
X84150D01*
G01X69100Y549200D02*
X71300Y547000D01*
G01D02*
X74500D01*
G01X88271Y552998D02*
X86263D01*
G01D02*
X85350Y553911D01*
G01D02*
X84839D01*
G01D02*
X84250Y554500D01*
G01X101193Y552126D02*
X96108D01*
G01D02*
X94796Y553438D01*
G01D02*
X92473D01*
G01D02*
X92033Y552998D01*
G01D02*
X88271D01*
G01X80650Y550400D02*
X77400D01*
G01X84900Y585750D02*
X88350Y589200D01*
G01D02*
Y590300D01*
G01D02*
X88388Y590338D01*
G01D02*
Y596545D01*
G01D02*
X86933Y598000D01*
G01X92000Y605500D02*
X88388Y601888D01*
G01D02*
Y599455D01*
G01D02*
X86933Y598000D01*
G01D02*
X85250D01*
G01X66000Y594250D02*
Y598250D01*
G01X69500Y586000D02*
X73750D01*
G01D02*
Y582000D01*
G01Y586000D02*
X74269Y586519D01*
G01D02*
Y599470D01*
G01X91750Y595440D02*
Y592500D01*
G01D02*
X92000Y592250D01*
G01D02*
Y591200D01*
G01X70000Y615500D02*
Y611750D01*
G01D02*
X72000Y609750D01*
G01X83562Y610519D02*
X84331D01*
G01D02*
X88000Y606850D01*
G01X85250Y600560D02*
Y605000D01*
G01D02*
X83750Y606500D01*
G01D02*
X83562Y606688D01*
G01D02*
Y610519D01*
G01X72000Y606250D02*
X69547D01*
G01D02*
X67508Y608289D01*
G01X72000Y606250D02*
X76000D01*
G01D02*
X76250Y606500D01*
G01D02*
X80250D01*
G01X78500Y615500D02*
Y612250D01*
G01D02*
X76000Y609750D01*
G01X66000Y590750D02*
X65780Y590530D01*
G01D02*
Y586777D01*
G01D02*
X67677D01*
G01D02*
X68738Y587838D01*
G01D02*
X70338D01*
G01D02*
X71709Y589209D01*
G01D02*
Y592970D01*
G01X72300Y637300D02*
X77538Y632062D01*
G01D02*
X82000D01*
G01D02*
X83200Y630862D01*
G01D02*
Y623400D01*
G01D02*
X86238Y620362D01*
G01D02*
X92562D01*
G01D02*
X97500Y625300D01*
G01D02*
Y631750D01*
G01X99250D02*
X97500D01*
G01X64500Y615500D02*
X70000D01*
G01X86750Y646000D02*
X78200D01*
G01X90250D02*
Y642000D01*
G01D02*
X89500Y641250D01*
G01D02*
Y628750D01*
G01D02*
Y622700D01*
G01D02*
X89600Y622600D01*
G01X100490Y635250D02*
X97500D01*
G01X92060D02*
X97500D01*
G01X84000Y615500D02*
X78500D01*
G01X73717Y632517D02*
X71434Y634800D01*
G01X78500Y624500D02*
Y627734D01*
G01D02*
X73717Y632517D01*
G01X80950Y705400D02*
X80700Y705150D01*
G01D02*
X76450D01*
G01D02*
X70750D01*
G01D02*
X69700Y706200D01*
G01X66100D02*
X69700D01*
G01X64974Y689980D02*
X65350Y690356D01*
G01X74500Y713400D02*
X71300D01*
G01D02*
X70700Y714000D01*
G01D02*
X68400Y716300D01*
G01X86678Y715878D02*
X85700Y714900D01*
G01D02*
X85000D01*
G01D02*
X83500D01*
G01D02*
X82151Y716249D01*
G01X97925Y690925D02*
X96075Y689075D01*
G01D02*
Y687900D01*
G01X98450Y685525D02*
X96075Y687900D01*
G01X71900D02*
X82075D01*
G01D02*
Y683175D01*
G01D02*
X83350Y681900D01*
G01X87450D02*
X83350D01*
G01X85500Y706800D02*
X86000Y706300D01*
G01D02*
Y702700D01*
G01D02*
X85450Y702150D01*
G01X85950Y695400D02*
X85450Y695900D01*
G01D02*
Y702150D01*
G01X99950Y695400D02*
X85950D01*
G01X85500Y706800D02*
X84300D01*
G01D02*
X83000Y705500D01*
G01D02*
Y703950D01*
G01D02*
X80950Y701900D01*
G01X74600Y731050D02*
X71835Y733815D01*
G01D02*
X68139D01*
G01D02*
X68038Y733916D01*
G01D02*
X64050D01*
G01X74600Y731050D02*
X78100D01*
G01D02*
X78350Y731300D01*
G01X67800Y749100D02*
Y746900D01*
G01D02*
X64350Y743450D01*
G01D02*
Y741790D01*
G01X64050Y731947D02*
X70203D01*
G01D02*
X74600Y727550D01*
G01D02*
X78100D01*
G01D02*
X78350Y727300D01*
G01X81850D02*
X85600D01*
G01D02*
X85800Y727500D01*
G01X68400Y716300D02*
Y719200D01*
G01X86678Y720600D02*
Y715878D01*
G01X82151Y716249D02*
Y722141D01*
G01D02*
X81092Y723200D01*
G01D02*
X79250D01*
G01X86678Y720600D02*
X85495D01*
G01D02*
X84695Y721400D01*
G01D02*
X83922D01*
G01X68900Y730000D02*
X68700D01*
G01D02*
X68679Y729979D01*
G01D02*
X64050D01*
G01X79900Y749300D02*
Y745250D01*
G01D02*
X79550Y744900D01*
G01X73800Y749600D02*
X67112Y742912D01*
G01D02*
Y740641D01*
G01D02*
X66292Y739821D01*
G01D02*
X64050D01*
G01X75750Y719300D02*
X75650Y719200D01*
G01D02*
X71000D01*
G01D02*
X64350Y725850D01*
G01D02*
Y728010D01*
G01X75750Y723200D02*
Y719300D01*
G01X64050Y735884D02*
X68120D01*
G01D02*
X68465Y736229D01*
G01X86678Y722200D02*
X90850D01*
G01D02*
X91800Y723150D01*
G01X89600Y727900D02*
Y725900D01*
G01D02*
X91800Y723700D01*
G01D02*
Y723150D01*
G01X81850Y731300D02*
X85500D01*
G01D02*
X85800Y731000D01*
G01X79550Y757900D02*
X76600D01*
G01D02*
X73900Y755200D01*
G01X79550Y757900D02*
Y762150D01*
G01D02*
X79800Y762400D01*
G01D02*
Y766650D01*
G01D02*
X79550Y766900D01*
G01X73900Y755200D02*
X67800Y749100D01*
G01X64900Y770900D02*
X65000Y770800D01*
G01D02*
Y766550D01*
G01Y763050D02*
X69650D01*
G01D02*
X69800Y762900D01*
G01D02*
X74050D01*
G01D02*
X74300Y762650D01*
G01X65000Y763050D02*
Y752400D01*
G01D02*
X64400Y751800D01*
G01X79550Y753700D02*
X77900D01*
G01D02*
X73800Y749600D01*
G01X79550Y753700D02*
Y749650D01*
G01D02*
X79900Y749300D01*
G01X97248Y813797D02*
X93697D01*
G01D02*
X93100Y813200D01*
G01X97248Y820203D02*
X94603D01*
G01D02*
X93300Y818900D01*
G01X109970Y155890D02*
Y133630D01*
G01D02*
X108050Y131710D01*
G01Y135210D02*
X104050D01*
G01X108224Y158387D02*
Y144424D01*
G01X104611Y192016D02*
Y145611D01*
G01X110820Y195189D02*
Y156740D01*
G01D02*
X109970Y155890D01*
G01X111050Y207700D02*
Y203300D01*
G01Y211700D02*
Y207700D01*
G01Y203300D02*
X106288Y198538D01*
G01D02*
Y193693D01*
G01D02*
X104611Y192016D01*
G01X107050Y209150D02*
X105800Y207900D01*
G01D02*
X105300D01*
G01D02*
X104100D01*
G01D02*
X103100Y208900D01*
G01D02*
Y211600D01*
G01X111967Y199632D02*
X111319Y198984D01*
G01D02*
Y195688D01*
G01D02*
X110820Y195189D01*
G01X110550Y212200D02*
X111050Y211700D01*
G01X107050Y212200D02*
Y209150D01*
G01X97750Y278578D02*
Y276300D01*
G01X100953Y257066D02*
Y262921D01*
G01D02*
X104172Y266140D01*
G01D02*
X107340D01*
G01X99057Y281582D02*
X102100D01*
G01D02*
X102499Y281183D01*
G01X100500Y285300D02*
X98268Y287532D01*
G01X104000Y286200D02*
X105850Y284350D01*
G01D02*
Y283150D01*
G01D02*
X106500Y282500D01*
G01D02*
Y280650D01*
G01X104000Y286200D02*
X101243Y288957D01*
G01X120700Y282400D02*
Y283100D01*
G01D02*
X121350Y283750D01*
G01D02*
Y287500D01*
G01X103940Y319780D02*
X105172Y321012D01*
G01D02*
X107558D01*
G01X103998Y340800D02*
X99912D01*
G01D02*
X99887Y340825D01*
G01X100277Y336077D02*
X103998Y339798D01*
G01D02*
Y340800D01*
G01X103617Y332765D02*
X98765D01*
G01D02*
X98400Y332400D01*
G01X104150Y324100D02*
X108850D01*
G01D02*
X114838Y330088D01*
G01D02*
Y336138D01*
G01D02*
X122000Y343300D01*
G01X113000Y336000D02*
X112775Y336225D01*
G01D02*
X111945D01*
G01D02*
X105942Y330222D01*
G01D02*
X105622D01*
G01D02*
X104050Y328650D01*
G01D02*
Y328600D01*
G01X136700Y350500D02*
X121899Y335699D01*
G01D02*
Y331900D01*
G01D02*
X119704Y329705D01*
G01D02*
X119610D01*
G01D02*
X111511Y321606D01*
G01D02*
Y321512D01*
G01D02*
X105649Y315650D01*
G01D02*
X103990D01*
G01X102000Y364700D02*
X103260D01*
G01D02*
X105835Y362125D01*
G01D02*
Y373069D01*
G01D02*
X107282Y374516D01*
G01D02*
X112307D01*
G01D02*
X117938Y380147D01*
G01X105896Y362064D02*
X105835Y362125D01*
G01X99760Y375340D02*
X105622D01*
G01D02*
X106223Y375941D01*
G01D02*
X109407D01*
G01D02*
X112122Y378656D01*
G01X112396Y356944D02*
Y355406D01*
G01D02*
X110984Y353994D01*
G01D02*
X110868D01*
G01D02*
X109285Y352411D01*
G01D02*
X110322Y351374D01*
G01D02*
Y347616D01*
G01D02*
X106956Y344250D01*
G01D02*
X104048D01*
G01D02*
X103998Y344300D01*
G01X111900Y344200D02*
X115360D01*
G01D02*
X119830Y348670D01*
G01X117761Y372556D02*
X117811Y372506D01*
G01D02*
X119599D01*
G01D02*
X119649Y372556D01*
G01D02*
X125309D01*
G01D02*
X128716Y369149D01*
G01D02*
Y357556D01*
G01D02*
X119830Y348670D01*
G01X117761Y372556D02*
X116361Y371156D01*
G01D02*
X108247D01*
G01X117300Y361700D02*
X115104Y359504D01*
G01D02*
X105896D01*
G01X99887Y348487D02*
Y344325D01*
G01X125718Y383302D02*
Y383343D01*
G01D02*
X126175Y383800D01*
G01D02*
X130367D01*
G01D02*
X131614Y385047D01*
G01X117938Y380147D02*
Y389507D01*
G01D02*
X114996Y392449D01*
G01D02*
Y395657D01*
G01D02*
X108249Y402404D01*
G01D02*
X106148D01*
G01D02*
X104808Y403744D01*
G01D02*
Y405542D01*
G01D02*
Y410691D01*
G01D02*
X102373Y413126D01*
G01X112250Y385000D02*
Y378784D01*
G01D02*
X112122Y378656D01*
G01X112250Y388600D02*
Y385000D01*
G01X104507Y392184D02*
X105000Y392677D01*
G01D02*
Y397200D01*
G01D02*
X103158Y399042D01*
G01D02*
X102248D01*
G01X100400Y392184D02*
X104507D01*
G01X100200Y388350D02*
Y390300D01*
G01D02*
X100000Y390500D01*
G01D02*
Y391784D01*
G01D02*
X100400Y392184D01*
G01X124290Y401910D02*
Y399010D01*
G01D02*
X132347Y390953D01*
G01X100200Y384850D02*
X98200Y386850D01*
G01D02*
Y391219D01*
G01D02*
X98162Y391257D01*
G01D02*
Y393111D01*
G01D02*
X98200Y393149D01*
G01D02*
Y402563D01*
G01X127633Y441705D02*
Y446663D01*
G01X116300Y436400D02*
X120200D01*
G01X120252Y440302D02*
Y436452D01*
G01D02*
X120200Y436400D01*
G01X112184Y441150D02*
Y437194D01*
G01D02*
X112978Y436400D01*
G01D02*
X116300D01*
G01X131004Y422710D02*
X134768Y426474D01*
G01X120252Y445676D02*
Y443802D01*
G01X138249Y425800D02*
X131304Y418855D01*
G01X130633Y444763D02*
X134670Y448800D01*
G01X131659Y436700D02*
X131355Y437004D01*
G01X132899Y440240D02*
X131355Y438696D01*
G01X129547Y480649D02*
Y475087D01*
G01D02*
X121937Y467477D01*
G01D02*
Y467277D01*
G01D02*
X120680Y466020D01*
G01X100911Y477241D02*
X101170Y477500D01*
G01D02*
X103158D01*
G01D02*
X106258Y480600D01*
G01X97900Y464000D02*
X99900Y466000D01*
G01D02*
X102540D01*
G01D02*
X105563Y469023D01*
G01D02*
X106447D01*
G01D02*
X110262Y472838D01*
G01D02*
Y476138D01*
G01D02*
X116311Y482187D01*
G01X102032Y475274D02*
X103974D01*
G01D02*
X115648Y486948D01*
G01X111421Y467542D02*
X115306Y471427D01*
G01D02*
Y475594D01*
G01D02*
X120098Y480386D01*
G01X111421Y467542D02*
X111427D01*
G01D02*
Y467538D01*
G01D02*
X111400Y467511D01*
G01D02*
Y461350D01*
G01D02*
X111500Y461250D01*
G01X120500Y461000D02*
X123362Y463862D01*
G01D02*
Y466886D01*
G01D02*
X131258Y474782D01*
G01D02*
Y481244D01*
G01X100500Y449100D02*
X107700D01*
G01D02*
X107900Y448900D01*
G01X127633Y446663D02*
X129520Y448550D01*
G01D02*
Y448660D01*
G01X134408Y472892D02*
X127638Y466122D01*
G01D02*
Y464227D01*
G01D02*
X126838Y463427D01*
G01D02*
Y457662D01*
G01D02*
X128500Y456000D01*
G01X129076Y462500D02*
Y464230D01*
G01D02*
X135846Y471000D01*
G01X133000Y461250D02*
X130326D01*
G01D02*
X129076Y462500D01*
G01X115673Y464911D02*
X115500Y464738D01*
G01D02*
Y461250D01*
G01X115673Y464911D02*
Y468773D01*
G01D02*
X117212Y470312D01*
G01D02*
Y475588D01*
G01D02*
X121636Y480012D01*
G01X126397Y480649D02*
Y477249D01*
G01D02*
X122948Y473800D01*
G01D02*
X122600D01*
G01X125500Y466000D02*
X132696Y473196D01*
G01X116235Y451285D02*
X120000D01*
G01X101312Y454488D02*
Y453793D01*
G01D02*
X102955Y452150D01*
G01D02*
X115370D01*
G01D02*
X116235Y451285D01*
G01X122406Y447830D02*
X120252Y445676D01*
G01X123696Y454452D02*
X122406Y453162D01*
G01D02*
Y447830D01*
G01X101200Y470400D02*
X102000D01*
G01D02*
X103277Y471677D01*
G01D02*
Y472561D01*
G01D02*
X116116Y485400D01*
G01X124959Y481244D02*
Y478359D01*
G01D02*
X122700Y476100D01*
G01X128000Y481135D02*
Y476652D01*
G01D02*
X122848Y471500D01*
G01D02*
X122600D01*
G01X117444Y479111D02*
X113166Y474833D01*
G01D02*
Y472595D01*
G01D02*
X107000Y466429D01*
G01D02*
Y465052D01*
G01D02*
X106983Y465035D01*
G01D02*
X107000Y465018D01*
G01D02*
Y461750D01*
G01D02*
X107500Y461250D01*
G01X103500D02*
X101450D01*
G01D02*
X100000Y462700D01*
G01X116948Y480649D02*
X111949Y475650D01*
G01D02*
Y473049D01*
G01D02*
X107048Y468148D01*
G01D02*
X106703D01*
G01D02*
X105966Y467411D01*
G01D02*
Y467410D01*
G01D02*
X103056Y464500D01*
G01D02*
X100800D01*
G01D02*
X100000Y463700D01*
G01D02*
Y462700D01*
G01X123247Y480649D02*
Y478947D01*
G01D02*
X122700Y478400D01*
G01X116948Y505846D02*
X115373Y504271D01*
G01X129547Y490098D02*
X127973Y488524D01*
G01X123247Y486948D02*
X121709Y488486D01*
G01D02*
X114144D01*
G01D02*
X106258Y480600D01*
G01X100727Y509613D02*
X102038Y510924D01*
G01D02*
Y511157D01*
G01D02*
X106176Y515295D01*
G01X116311Y482187D02*
X117687D01*
G01D02*
X119299Y483799D01*
G01D02*
X120098D01*
G01X99800Y511851D02*
X103111Y515162D01*
G01X99800Y511851D02*
X99614Y512037D01*
G01X115648Y486948D02*
X116948D01*
G01X120098Y480386D02*
Y480649D01*
G01X131258Y481244D02*
X132696Y482682D01*
G01X123247Y505846D02*
X121673Y504272D01*
G01X123247Y496397D02*
Y496396D01*
G01D02*
X121673Y494822D01*
G01X126397Y496397D02*
X127971Y494823D01*
G01X126397Y502696D02*
X124823Y501122D01*
G01X102000Y497700D02*
X102734Y498434D01*
G01D02*
X108640D01*
G01D02*
X113837Y503631D01*
G01D02*
X113835Y503634D01*
G01D02*
Y504908D01*
G01D02*
X116211Y507284D01*
G01D02*
X120419D01*
G01D02*
X122131Y508996D01*
G01D02*
X123247D01*
G01X121636Y480012D02*
Y481213D01*
G01D02*
X122610Y482187D01*
G01D02*
X123810D01*
G01D02*
X124959Y483336D01*
G01D02*
Y485510D01*
G01D02*
X126397Y486948D01*
G01X129547Y493248D02*
X127973Y491674D01*
G01X106000Y511600D02*
X107983Y513583D01*
G01X118660D02*
X120098Y512145D01*
G01X101439Y507920D02*
X105119Y511600D01*
G01D02*
X106000D01*
G01X129547Y512145D02*
X127973Y510571D01*
G01X120098Y505846D02*
Y505836D01*
G01D02*
X118500Y504238D01*
G01X129547Y499547D02*
X127973Y497973D01*
G01X129547Y496397D02*
X131121Y494823D01*
G01X126397Y512145D02*
X124823Y510571D01*
G01X116116Y485400D02*
X118550D01*
G01D02*
X120098Y486948D01*
G01X126397Y483799D02*
Y482682D01*
G01D02*
X124959Y481244D01*
G01X123247Y502696D02*
X121673Y501122D01*
G01X132696Y490098D02*
X131122Y488524D01*
G01X129547Y483799D02*
Y482682D01*
G01D02*
X128000Y481135D01*
G01X126397Y490098D02*
X124822Y488523D01*
G01X129547Y508996D02*
X131121Y510570D01*
G01X99820Y505670D02*
X101220D01*
G01D02*
X104050Y508500D01*
G01D02*
X106620D01*
G01D02*
X110265Y512145D01*
G01D02*
X116948D01*
G01X123247Y499547D02*
X121673Y497973D01*
G01X132696Y493248D02*
X131122Y491674D01*
G01X123247Y483799D02*
X122273D01*
G01D02*
X120661Y482187D01*
G01D02*
X119461D01*
G01D02*
X118486Y481212D01*
G01D02*
Y480012D01*
G01D02*
X117585Y479111D01*
G01D02*
X117444D01*
G01X126397Y493248D02*
X124823Y494822D01*
G01X129547Y502696D02*
X127973Y501122D01*
G01X123247Y490098D02*
X121673Y491672D01*
G01X126397Y508996D02*
X128109Y507284D01*
G01D02*
X130142D01*
G01D02*
X130985Y506441D01*
G01D02*
Y504300D01*
G01X123247Y512145D02*
X121673Y510571D01*
G01X132696Y486948D02*
X131122Y485374D01*
G01X120098Y518444D02*
X118442Y520100D01*
G01D02*
X102600D01*
G01D02*
X101325Y518825D01*
G01D02*
X101309D01*
G01X107860Y547162D02*
X113157Y541865D01*
G01D02*
X113193D01*
G01D02*
X114566Y540492D01*
G01D02*
X116948D01*
G01X132696Y544032D02*
X131000Y545728D01*
G01D02*
Y549861D01*
G01X129547Y521594D02*
X131121Y523168D01*
G01X106176Y515295D02*
X116948D01*
G01X123247Y531043D02*
X121673Y532617D01*
G01X98237Y542849D02*
X100091D01*
G01D02*
X100866Y542074D01*
G01D02*
X105091D01*
G01D02*
X105641Y541524D01*
G01D02*
X107706D01*
G01D02*
X107830Y541400D01*
G01D02*
X108400D01*
G01D02*
X114100Y535700D01*
G01D02*
X118590D01*
G01D02*
X120098Y534192D01*
G01X126397Y521594D02*
X124822Y520019D01*
G01X103111Y515162D02*
X104062D01*
G01D02*
X105633Y516733D01*
G01D02*
X117543D01*
G01D02*
X118981Y515295D01*
G01D02*
X120098D01*
G01X126397Y527893D02*
X124823Y529467D01*
G01X99164Y540611D02*
X99202Y540649D01*
G01D02*
X107343D01*
G01D02*
X113800Y534192D01*
G01D02*
X116948D01*
G01X97861Y540611D02*
X99164D01*
G01X123247Y543641D02*
X121673Y545215D01*
G01X116948Y537342D02*
X114500D01*
G01D02*
X107530Y544312D01*
G01X129547Y524744D02*
X127973Y523170D01*
G01X129547Y527893D02*
X131121Y529467D01*
G01X99476Y534446D02*
X99522Y534400D01*
G01D02*
X110243D01*
G01D02*
X113600Y531043D01*
G01D02*
X116948D01*
G01X101894Y521594D02*
X116948D01*
G01X99600Y546200D02*
X100063Y545737D01*
G01D02*
X108047D01*
G01D02*
X112794Y540990D01*
G01D02*
X112830D01*
G01D02*
X115020Y538800D01*
G01D02*
X118640D01*
G01D02*
X120098Y537342D01*
G01X123247Y518444D02*
X121673Y516870D01*
G01D02*
Y513721D01*
G01X107983Y513583D02*
X118660D01*
G01X126397Y518444D02*
X127971Y520018D01*
G01X123247Y534192D02*
X121673Y535766D01*
G01X129547Y515295D02*
X131121Y513721D01*
G01X129547Y518444D02*
X131121Y520018D01*
G01X103300Y537800D02*
X108400D01*
G01D02*
X113600Y532600D01*
G01D02*
X118541D01*
G01D02*
X120098Y531043D01*
G01X99050Y537800D02*
X103300D01*
G01X126397Y531043D02*
X124823Y532617D01*
G01X106436Y552336D02*
X113593Y545179D01*
G01D02*
X118560D01*
G01D02*
X120098Y543641D01*
G01X123247Y515295D02*
X124821Y513721D01*
G01X103313Y531239D02*
X104052Y530500D01*
G01D02*
X111000D01*
G01D02*
X115200Y526300D01*
G01D02*
X118542D01*
G01D02*
X120098Y524744D01*
G01X100383Y531239D02*
X103313D01*
G01X101143Y523893D02*
X103289D01*
G01D02*
X112707D01*
G01D02*
X113500Y523100D01*
G01D02*
X118592D01*
G01D02*
X120098Y521594D01*
G01Y540492D02*
X118560Y542030D01*
G01D02*
X117603D01*
G01D02*
X117591Y542042D01*
G01D02*
X116305D01*
G01D02*
X116293Y542030D01*
G01D02*
X114284D01*
G01D02*
X113561Y542753D01*
G01D02*
X113525D01*
G01D02*
X106978Y549300D01*
G01X123247Y524744D02*
X121673Y523170D01*
G01X126397Y524744D02*
X124823Y523170D01*
G01X99829Y527492D02*
Y527520D01*
G01X116948Y524744D02*
X114300D01*
G01D02*
X111468Y527576D01*
G01D02*
X99913D01*
G01D02*
X99829Y527492D01*
G01X132696Y541312D02*
X130985Y543022D01*
G01D02*
Y544236D01*
G01D02*
X129868Y545353D01*
G01D02*
X128836D01*
G01D02*
X127900Y546289D01*
G01D02*
Y547321D01*
G01X123247Y521594D02*
X121673Y520020D01*
G01X116948Y543641D02*
X113893D01*
G01D02*
X105697Y551837D01*
G01X129547Y531043D02*
X127973Y529469D01*
G01X131400Y535900D02*
X130985Y536315D01*
G01D02*
Y538639D01*
G01D02*
X131400Y539054D01*
G01X116948Y518444D02*
X104144D01*
G01D02*
X103100Y517400D01*
G01D02*
X101900D01*
G01D02*
X97962Y513462D01*
G01X123247Y537342D02*
X121673Y538916D01*
G01X126397Y515295D02*
X127971Y513721D01*
G01X131900Y550600D02*
X131100Y551400D01*
G01D02*
Y559100D01*
G01D02*
X130600Y559600D01*
G01D02*
X128200D01*
G01D02*
X127700Y559100D01*
G01D02*
Y557200D01*
G01D02*
X126962Y556462D01*
G01D02*
X124900D01*
G01X147200Y570637D02*
X124337D01*
G01D02*
X122547Y568847D01*
G01D02*
Y567628D01*
G01X98008Y548438D02*
Y548338D01*
G01D02*
X99478D01*
G01D02*
X100654Y547162D01*
G01D02*
X107860D01*
G01X140400Y567787D02*
X127000D01*
G01D02*
X126500Y567287D01*
G01D02*
Y564414D01*
G01D02*
X124900Y562814D01*
G01X133500Y564937D02*
X129791D01*
G01D02*
X129350Y564496D01*
G01D02*
Y563073D01*
G01D02*
X125915Y559638D01*
G01D02*
X124900D01*
G01X131000Y549861D02*
X130100Y550761D01*
G01D02*
Y554424D01*
G01D02*
X129600Y554924D01*
G01D02*
X122547D01*
G01X136600Y566362D02*
X129200D01*
G01D02*
X127925Y565087D01*
G01D02*
Y563664D01*
G01D02*
X125537Y561276D01*
G01D02*
X122547D01*
G01X126801Y574386D02*
X128814D01*
G01D02*
X131138Y572062D01*
G01D02*
X151200D01*
G01X142800Y569212D02*
X126112D01*
G01D02*
X124900Y568000D01*
G01D02*
Y565990D01*
G01X100742Y554593D02*
X102073Y553262D01*
G01D02*
X105511D01*
G01D02*
X106436Y552336D01*
G01X106978Y549300D02*
X102300D01*
G01D02*
X101201Y550399D01*
G01D02*
X100886D01*
G01D02*
X100597Y550688D01*
G01X127900Y547321D02*
X125111Y550110D01*
G01D02*
X124847D01*
G01X105697Y551837D02*
X101482D01*
G01D02*
X101193Y552126D01*
G01X129547Y546791D02*
X129225Y547113D01*
G01D02*
Y549050D01*
G01D02*
X128750Y549525D01*
G01D02*
X127400D01*
G01D02*
X126900Y550025D01*
G01D02*
Y550925D01*
G01D02*
X127400Y551425D01*
G01D02*
X128750D01*
G01D02*
X129225Y551900D01*
G01D02*
Y552775D01*
G01D02*
X128714Y553286D01*
G01D02*
X124900D01*
G01X117197Y599921D02*
X115024D01*
G01D02*
X112100Y596997D01*
G01D02*
Y594500D01*
G01D02*
X111600Y594000D01*
G01D02*
X110200D01*
G01D02*
X109700Y594500D01*
G01D02*
Y598100D01*
G01D02*
X113900Y602300D01*
G01D02*
X114818D01*
G01D02*
X115622Y601496D01*
G01X126646Y596771D02*
X125208Y595333D01*
G01D02*
Y593159D01*
G01D02*
X122559Y590510D01*
G01D02*
X121385D01*
G01D02*
X120384Y589509D01*
G01D02*
Y588235D01*
G01D02*
X121109Y587509D01*
G01D02*
Y586100D01*
G01D02*
X120609Y585600D01*
G01D02*
X118800D01*
G01D02*
X118300Y586100D01*
G01D02*
Y589275D01*
G01D02*
X118773Y589748D01*
G01X120347Y596771D02*
Y595700D01*
G01D02*
X120847Y595200D01*
G01D02*
X121600D01*
G01D02*
X122058Y595658D01*
G01D02*
Y597887D01*
G01D02*
X121600Y598345D01*
G01D02*
X118773D01*
G01X120347Y599921D02*
X118773Y601495D01*
G01X120347Y612519D02*
X118773Y610945D01*
G01X131870Y608500D02*
X131370Y608000D01*
G01X117197Y596771D02*
Y595655D01*
G01D02*
X115435Y593893D01*
G01D02*
Y587100D01*
G01D02*
X114935Y586600D01*
G01D02*
X113900D01*
G01D02*
X113400Y587100D01*
G01D02*
Y596122D01*
G01D02*
X115623Y598345D01*
G01X123496Y599921D02*
X123000Y600417D01*
G01D02*
Y602425D01*
G01D02*
X123500Y602925D01*
G01D02*
X124570D01*
G01D02*
X125070Y602425D01*
G01D02*
Y598347D01*
G01X126646Y612519D02*
X125072Y610945D01*
G01X123496Y596771D02*
Y597888D01*
G01D02*
X121785Y599599D01*
G01D02*
Y601815D01*
G01D02*
X120566Y603034D01*
G01D02*
X118800D01*
G01D02*
X118300Y603534D01*
G01D02*
Y604172D01*
G01D02*
X118773Y604645D01*
G01X129795Y612519D02*
X129831Y612483D01*
G01D02*
Y610308D01*
G01D02*
X129900Y610239D01*
G01D02*
Y602092D01*
G01D02*
X129408Y601600D01*
G01D02*
X128713D01*
G01D02*
X128221Y602092D01*
G01D02*
Y610945D01*
G01X117197Y612519D02*
Y610900D01*
G01D02*
X116697Y610400D01*
G01D02*
X114700D01*
G01D02*
X114200Y610900D01*
G01D02*
Y613594D01*
G01D02*
X114700Y614094D01*
G01X123496Y612519D02*
X121922Y610945D01*
G01X126646Y599921D02*
X126837Y600112D01*
G01D02*
Y603463D01*
G01D02*
X126500Y603800D01*
G01D02*
X121400D01*
G01D02*
X120900Y604300D01*
G01D02*
Y606200D01*
G01D02*
X120300Y606800D01*
G01D02*
X117500D01*
G01D02*
X116800Y607500D01*
G01D02*
Y608400D01*
G01D02*
X117400Y609000D01*
G01D02*
X126146D01*
G01D02*
X126646Y608500D01*
G01D02*
Y606400D01*
G01X117197Y615669D02*
X109930Y622936D01*
G01D02*
X108064D01*
G01D02*
X104000Y627000D01*
G01D02*
X99250Y631750D01*
G01X123496Y615669D02*
X125070Y614095D01*
G01X102020Y633720D02*
X100490Y635250D01*
G01X114700Y614094D02*
X115622D01*
G01X129795Y615669D02*
X131369Y614095D01*
G01X126646Y615669D02*
X128220Y614095D01*
G01X120347Y615669D02*
Y615641D01*
G01D02*
X118805Y614099D01*
G01X119650Y714300D02*
Y716750D01*
G01Y707800D02*
Y714300D01*
G01X107000Y717800D02*
Y696700D01*
G01D02*
X101225Y690925D01*
G01D02*
X97925D01*
G01X98450Y681900D02*
Y685525D01*
G01Y681900D02*
X102450D01*
G01X119650Y716750D02*
X118060Y718340D01*
G01D02*
Y721650D01*
G01X124800Y745300D02*
X128850D01*
G01D02*
X128950Y745200D01*
G01X125740Y737950D02*
Y741300D01*
G01D02*
X124350Y742690D01*
G01D02*
Y744850D01*
G01D02*
X124800Y745300D01*
G01X118200Y782300D02*
X120900Y785000D01*
G01X126000Y780750D02*
Y784900D01*
G01X118250Y756000D02*
Y753850D01*
G01D02*
X120000Y752100D01*
G01D02*
X120500D01*
G01X122700Y756300D02*
Y753700D01*
G01D02*
X121100Y752100D01*
G01D02*
X120500D01*
G01X122700Y761300D02*
Y762700D01*
G01D02*
X128500Y768500D01*
G01X126000Y777250D02*
X128500Y774750D01*
G01D02*
Y768500D01*
G01X122700Y761300D02*
Y756300D01*
G01X114750Y756000D02*
X111300D01*
G01X120900Y785000D02*
X125900D01*
G01X126000Y784900D02*
X125900Y785000D01*
G01X162500Y222000D02*
X160000Y219500D01*
G01D02*
X156740D01*
G01X166890Y237540D02*
X162900D01*
G01D02*
X156740Y231380D01*
G01D02*
Y228500D01*
G01X144667Y329390D02*
X142077Y326800D01*
G01D02*
X138684D01*
G01D02*
X137768Y325884D01*
G01D02*
Y322641D01*
G01X142063Y322350D02*
X138059D01*
G01D02*
X137768Y322641D01*
G01X149564Y322277D02*
X151540Y324253D01*
G01D02*
X161791D01*
G01D02*
X163850Y326312D01*
G01D02*
Y329077D01*
G01D02*
X161116Y331811D01*
G01D02*
X152435D01*
G01X145168Y317749D02*
X145039Y317878D01*
G01D02*
Y321826D01*
G01D02*
X145563Y322350D01*
G01X145168Y317749D02*
X145767D01*
G01D02*
X149564Y321546D01*
G01D02*
Y322277D01*
G01X134800Y329600D02*
X136100Y328300D01*
G01D02*
X138279D01*
G01D02*
X141607Y331628D01*
G01D02*
X146754D01*
G01D02*
X150421Y327961D01*
G01D02*
Y327936D01*
G01D02*
X159935D01*
G01X150000Y383079D02*
Y373974D01*
G01D02*
X151760Y372214D01*
G01X156573Y371799D02*
X152175D01*
G01D02*
X151760Y372214D01*
G01X163900Y383739D02*
Y368900D01*
G01D02*
X160303Y365303D01*
G01D02*
X145500Y350500D01*
G01D02*
X136700D01*
G01X140047Y395950D02*
Y398223D01*
G01D02*
X139360Y398910D01*
G01D02*
X134984D01*
G01D02*
X132778Y401116D01*
G01D02*
Y401706D01*
G01X134571Y406346D02*
X132778Y404553D01*
G01D02*
Y401706D01*
G01X131614Y385047D02*
X136000D01*
G01X133812Y414712D02*
Y410605D01*
G01D02*
X134571Y409846D01*
G01X151600Y413452D02*
Y409750D01*
G01X155700D02*
X151600D01*
G01X132347Y390953D02*
X136000D01*
G01X150000Y388984D02*
X158655D01*
G01D02*
X163900Y383739D01*
G01X157065Y395331D02*
X157100Y395366D01*
G01D02*
Y396600D01*
G01D02*
X154050Y399650D01*
G01D02*
Y402200D01*
G01X150000Y392921D02*
X156021D01*
G01D02*
X157065Y393965D01*
G01D02*
Y395331D01*
G01X135250Y443740D02*
Y444643D01*
G01D02*
X137344Y446737D01*
G01X134768Y426474D02*
Y429438D01*
G01D02*
Y431029D01*
G01D02*
X143976Y440237D01*
G01D02*
Y455526D01*
G01X133812Y414712D02*
X136500Y417400D01*
G01D02*
X147652D01*
G01D02*
X151600Y413452D01*
G01X151676Y446951D02*
Y441106D01*
G01D02*
X138249Y427679D01*
G01D02*
Y425800D01*
G01X152978Y435602D02*
Y434738D01*
G01D02*
X143073Y424833D01*
G01X143248Y420306D02*
X142870Y420684D01*
G01D02*
Y424630D01*
G01D02*
X143073Y424833D01*
G01X137000Y436700D02*
X131659D01*
G01X135250Y440240D02*
X132899D01*
G01X131355Y438696D02*
Y437004D01*
G01X164222Y457919D02*
X161360Y455057D01*
G01D02*
Y450610D01*
G01D02*
X159829Y449079D01*
G01D02*
X159239D01*
G01X168320Y462990D02*
X162790Y468520D01*
G01D02*
Y470930D01*
G01D02*
X159605Y474115D01*
G01D02*
Y482361D01*
G01X138930Y465660D02*
X138995Y465725D01*
G01D02*
Y480649D01*
G01X154500Y466000D02*
Y469400D01*
G01D02*
X153305Y470595D01*
G01D02*
Y482361D01*
G01X150632Y453605D02*
X150174Y454063D01*
G01D02*
Y458541D01*
G01X151594Y480649D02*
Y468944D01*
G01D02*
X152100Y468438D01*
G01D02*
Y463150D01*
G01D02*
X150200Y461250D01*
G01D02*
Y458567D01*
G01D02*
X150174Y458541D01*
G01X154743Y480649D02*
Y471557D01*
G01D02*
X156638Y469662D01*
G01D02*
Y463038D01*
G01D02*
X154700Y461100D01*
G01X149461Y466837D02*
X149437D01*
G01D02*
X146200Y463600D01*
G01D02*
Y461250D01*
G01X148444Y480649D02*
Y472300D01*
G01D02*
X149700Y471044D01*
G01D02*
Y467076D01*
G01D02*
X149461Y466837D01*
G01X134408Y481244D02*
Y472892D01*
G01X135846Y471000D02*
Y480649D01*
G01X133000Y461250D02*
X137000D01*
G01X162577Y447721D02*
X163440Y448584D01*
G01D02*
Y453020D01*
G01X158790Y458450D02*
X158063Y459177D01*
G01D02*
Y470537D01*
G01D02*
X156455Y472145D01*
G01D02*
Y482361D01*
G01X141500Y461400D02*
Y467524D01*
G01D02*
X140707Y468317D01*
G01D02*
Y476551D01*
G01D02*
X140457Y476801D01*
G01D02*
Y479399D01*
G01X132696Y473196D02*
Y480649D01*
G01X143976Y455526D02*
X146200Y457750D01*
G01X134090Y465780D02*
Y466000D01*
G01D02*
X137557Y469467D01*
G01D02*
Y481244D01*
G01X169399Y470740D02*
X162754Y477385D01*
G01D02*
Y482361D01*
G01X164268Y462983D02*
X161119Y459834D01*
G01D02*
Y457019D01*
G01D02*
X159820Y455720D01*
G01D02*
Y453247D01*
G01D02*
X159082Y452509D01*
G01X146431Y453528D02*
X147209D01*
G01D02*
X150632Y450105D01*
G01D02*
X150602Y450075D01*
G01D02*
Y448025D01*
G01D02*
X151676Y446951D01*
G01X144520Y466070D02*
X145400Y466950D01*
G01D02*
Y478493D01*
G01D02*
X143845Y480048D01*
G01X144520Y466070D02*
X144300Y465850D01*
G01D02*
Y459000D01*
G01D02*
X142050Y456750D01*
G01D02*
X142000D01*
G01X134670Y448800D02*
X137500D01*
G01D02*
X141950Y453250D01*
G01D02*
X142000D01*
G01X175000Y468500D02*
X164192Y479308D01*
G01X142145Y479555D02*
X143547Y478153D01*
G01D02*
Y477976D01*
G01X161043Y480649D02*
Y476817D01*
G01D02*
X166515Y471345D01*
G01X160300Y465900D02*
Y470400D01*
G01D02*
X157893Y472807D01*
G01D02*
Y480649D01*
G01X161043Y490098D02*
X159469Y488524D01*
G01X135846Y493248D02*
X134272Y491674D01*
G01X154743Y490098D02*
X153169Y488524D01*
G01X157893Y486948D02*
X156319Y485374D01*
G01X157893Y493248D02*
X156319Y491674D01*
G01X157893Y490098D02*
X156318Y488523D01*
G01X159605Y482361D02*
X161043Y483799D01*
G01X145295Y490098D02*
X143721Y488524D01*
G01X138995Y490098D02*
X137421Y488524D01*
G01X151594Y493248D02*
X150020Y491674D01*
G01X153305Y482361D02*
X154743Y483799D01*
G01X132696Y482682D02*
Y483799D01*
G01X145295Y486948D02*
X143721Y485374D01*
G01X142145Y493248D02*
X140571Y491674D01*
G01X138995Y493248D02*
X137421Y491674D01*
G01X135846Y483799D02*
Y482682D01*
G01D02*
X134408Y481244D01*
G01X164192Y493248D02*
X162618Y491674D01*
G01X154743Y493248D02*
Y493247D01*
G01D02*
X153170Y491674D01*
G01X164192Y486948D02*
X162618Y485374D01*
G01X156455Y482361D02*
X157893Y483799D01*
G01X135846Y490098D02*
X134272Y488524D01*
G01X140457Y479399D02*
X140707Y479649D01*
G01D02*
Y482361D01*
G01D02*
X142145Y483799D01*
G01X154743Y486948D02*
X153169Y485374D01*
G01X137557Y481244D02*
X138995Y482682D01*
G01D02*
Y483799D01*
G01Y486948D02*
X137421Y485374D01*
G01X162754Y482361D02*
X164192Y483799D01*
G01X142145Y486948D02*
X140571Y485374D01*
G01X161043Y493248D02*
X159469Y491674D01*
G01X135846Y486948D02*
X134272Y485374D01*
G01X143845Y480048D02*
Y482349D01*
G01D02*
X145295Y483799D01*
G01X151594Y490098D02*
X150020Y488524D01*
G01X164192Y479308D02*
Y480649D01*
G01X142145Y490098D02*
X140570Y488523D01*
G01X142145Y480649D02*
Y479555D01*
G01X161043Y486948D02*
X159469Y485374D01*
G01X164192Y490098D02*
X162618Y488524D01*
G01X145295Y493248D02*
X143721Y491674D01*
G01X164192Y540492D02*
X165766Y542066D01*
G01X157893Y537342D02*
X159449Y538898D01*
G01X142145Y543641D02*
X140700Y545086D01*
G01D02*
Y547188D01*
G01X138995Y543641D02*
X137869D01*
G01D02*
X137369Y544141D01*
G01D02*
Y547369D01*
G01X154743Y540492D02*
X153251Y541984D01*
G01D02*
Y542021D01*
G01D02*
X153194Y542078D01*
G01X135846Y543641D02*
Y543643D01*
G01D02*
X134219Y545270D01*
G01D02*
Y547281D01*
G01X161043Y537342D02*
X162617Y538916D01*
G01X132696Y543641D02*
Y544032D01*
G01X157893Y534192D02*
X159443Y532642D01*
G01D02*
X159456D01*
G01X138995Y540492D02*
X137421Y542066D01*
G01X165904Y545353D02*
X164192Y543641D01*
G01X157893D02*
Y542400D01*
G01D02*
X157393Y541900D01*
G01D02*
X156800D01*
G01D02*
X156300Y542400D01*
G01D02*
Y544853D01*
G01D02*
X156800Y545353D01*
G01D02*
X158488D01*
G01D02*
X159537Y546402D01*
G01D02*
Y548256D01*
G01X151594Y543641D02*
X153100Y545147D01*
G01D02*
Y549038D01*
G01X138995Y537342D02*
X137421Y535768D01*
G01X135846Y534192D02*
X134272Y532618D01*
G01X135846Y537342D02*
X134272Y535768D01*
G01X154743Y537342D02*
Y536000D01*
G01D02*
X155113Y535630D01*
G01D02*
X156085D01*
G01D02*
X156455Y536000D01*
G01D02*
Y538699D01*
G01D02*
X156100Y539054D01*
G01D02*
X153343D01*
G01D02*
X153188Y538899D01*
G01X151594Y537342D02*
X153131Y535805D01*
G01D02*
Y535768D01*
G01D02*
X153132Y535767D01*
G01X145295Y537342D02*
Y537376D01*
G01D02*
X143718Y538953D01*
G01X148444Y540492D02*
Y540543D01*
G01D02*
X147000Y541987D01*
G01D02*
Y547287D01*
G01X142145Y534192D02*
X140571Y532618D01*
G01X148444Y534192D02*
X147000Y535636D01*
G01D02*
X146964D01*
G01D02*
X146858Y535742D01*
G01X148444Y537342D02*
Y537379D01*
G01D02*
X146869Y538954D01*
G01X161043Y534192D02*
X162617Y535766D01*
G01X142145Y540492D02*
X140571Y538918D01*
G01D02*
X137421D01*
G01X145295Y543641D02*
X143619Y545317D01*
G01D02*
Y547371D01*
G01X161043Y540492D02*
X162617Y542066D01*
G01X151594Y540492D02*
X151556D01*
G01D02*
X149981Y538917D01*
G01X157893Y540492D02*
X159449Y542048D01*
G01X164192Y534192D02*
X162618Y532618D01*
G01X132696Y540492D02*
Y541312D01*
G01X145295Y540492D02*
X145264D01*
G01D02*
X143686Y542070D01*
G01X142145Y537342D02*
X140570Y535767D01*
G01X164192Y537342D02*
X165766Y538916D01*
G01X151594Y534192D02*
Y533100D01*
G01D02*
X151094Y532600D01*
G01D02*
X150485D01*
G01D02*
X149985Y533100D01*
G01D02*
Y535771D01*
G01X138995Y534192D02*
X137421Y532618D01*
G01X135846Y540492D02*
X134272Y542066D01*
G01X132696Y537342D02*
Y536400D01*
G01D02*
X132196Y535900D01*
G01D02*
X131400D01*
G01Y539054D02*
X134132D01*
G01D02*
X134270Y538916D01*
G01X153187Y532636D02*
X154743Y534192D01*
G01X132696Y546791D02*
X131900Y547587D01*
G01D02*
Y550600D01*
G01X140700Y547188D02*
X138000Y549888D01*
G01D02*
Y559538D01*
G01D02*
X147698Y569236D01*
G01D02*
Y570139D01*
G01D02*
X147200Y570637D01*
G01X137369Y547369D02*
X135150Y549588D01*
G01D02*
Y559538D01*
G01D02*
X135149Y559539D01*
G01D02*
Y560719D01*
G01D02*
X140900Y566470D01*
G01D02*
Y567287D01*
G01D02*
X140400Y567787D01*
G01X134219Y547281D02*
X134134Y547366D01*
G01D02*
Y547386D01*
G01D02*
X132900Y548620D01*
G01D02*
Y551638D01*
G01D02*
X132299Y552239D01*
G01D02*
Y561901D01*
G01D02*
X134000Y563602D01*
G01D02*
Y564437D01*
G01D02*
X133500Y564937D01*
G01X135846Y546791D02*
Y547293D01*
G01D02*
X133775Y549364D01*
G01D02*
Y552001D01*
G01D02*
X133724Y552052D01*
G01D02*
Y561310D01*
G01D02*
X137100Y564686D01*
G01D02*
Y565862D01*
G01D02*
X136600Y566362D01*
G01X157893Y546791D02*
Y549607D01*
G01D02*
X156200Y551300D01*
G01D02*
Y555700D01*
G01D02*
X152800Y559100D01*
G01D02*
X149200D01*
G01D02*
X148700Y559600D01*
G01D02*
Y561800D01*
G01D02*
X149200Y562300D01*
G01D02*
X154525D01*
G01D02*
X155000Y561825D01*
G01D02*
Y560100D01*
G01D02*
X155500Y559600D01*
G01D02*
X156400D01*
G01D02*
X156900Y560100D01*
G01D02*
Y562000D01*
G01D02*
X157400Y562500D01*
G01D02*
X158800D01*
G01D02*
X159300Y562000D01*
G01D02*
Y551856D01*
G01D02*
X159800Y551356D01*
G01D02*
X160700D01*
G01X153100Y549038D02*
X149975Y552163D01*
G01D02*
Y557125D01*
G01D02*
X149126Y557974D01*
G01D02*
X146814D01*
G01D02*
X145913Y557073D01*
G01D02*
Y551399D01*
G01D02*
X145514Y551000D01*
G01D02*
X144949D01*
G01D02*
X144550Y551399D01*
G01D02*
Y556100D01*
G01D02*
X144050Y556600D01*
G01D02*
X143451D01*
G01D02*
X142951Y556100D01*
G01D02*
Y555636D01*
G01X151594Y546791D02*
Y549006D01*
G01D02*
X149100Y551500D01*
G01D02*
Y554787D01*
G01D02*
X147451Y556436D01*
G01X164192Y546791D02*
Y546912D01*
G01D02*
X172362Y555082D01*
G01X151200Y572062D02*
X151700Y571562D01*
G01D02*
Y568311D01*
G01D02*
X151200Y567811D01*
G01D02*
X148289D01*
G01D02*
X139178Y558700D01*
G01D02*
Y550010D01*
G01D02*
X142145Y547043D01*
G01D02*
Y546791D01*
G01X147000Y547287D02*
X143251Y551036D01*
G01D02*
X142951D01*
G01X138995Y546791D02*
X138319Y547467D01*
G01D02*
Y548020D01*
G01D02*
X136575Y549764D01*
G01D02*
Y560129D01*
G01D02*
X143400Y566954D01*
G01D02*
Y568612D01*
G01D02*
X142800Y569212D01*
G01X143619Y547371D02*
X142761Y548229D01*
G01D02*
X142274D01*
G01D02*
X140276Y550227D01*
G01D02*
Y557439D01*
G01D02*
X149137Y566300D01*
G01D02*
X161280D01*
G01X145295Y546791D02*
Y546933D01*
G01D02*
X143124Y549104D01*
G01D02*
X142637D01*
G01D02*
X141226Y550516D01*
G01D02*
Y556373D01*
G01D02*
X148853Y564000D01*
G01D02*
X161280D01*
G01X140956Y581225D02*
Y579800D01*
G01D02*
X141456Y579300D01*
G01D02*
X143468D01*
G01D02*
X143968Y579800D01*
G01D02*
Y588898D01*
G01X136769Y580470D02*
X138769Y578470D01*
G01X151843Y612519D02*
Y611743D01*
G01D02*
X151806Y611706D01*
G01D02*
Y610000D01*
G01D02*
X151099Y609293D01*
G01D02*
X146893D01*
G01D02*
X146300Y608700D01*
G01D02*
Y606975D01*
G01D02*
X146800Y606475D01*
G01D02*
X156600D01*
G01D02*
X157100Y606975D01*
G01D02*
Y608900D01*
G01D02*
X156600Y609400D01*
G01D02*
X153900D01*
G01D02*
X153417Y609883D01*
G01D02*
Y610945D01*
G01X158142Y596771D02*
X159716Y595197D01*
G01X132945Y599921D02*
X134500Y601476D01*
G01D02*
Y605800D01*
G01D02*
X135000Y606300D01*
G01D02*
X139000D01*
G01D02*
X139500Y605800D01*
G01D02*
Y604200D01*
G01D02*
X139900Y603800D01*
G01D02*
X141200D01*
G01D02*
X141800Y604400D01*
G01D02*
Y608100D01*
G01D02*
X141400Y608500D01*
G01D02*
X131870D01*
G01X131370Y608000D02*
Y601496D01*
G01X161291Y596771D02*
X162865Y598345D01*
G01D02*
X166015D01*
G01X164441Y599921D02*
X164479Y599883D01*
G01D02*
X166652D01*
G01X148693Y599921D02*
Y602094D01*
G01D02*
X147754Y603033D01*
G01D02*
X144067D01*
G01D02*
X143300Y603800D01*
G01D02*
Y604800D01*
G01D02*
X143800Y605300D01*
G01D02*
X150268D01*
G01D02*
X150968Y604600D01*
G01D02*
Y602196D01*
G01D02*
X150268Y601496D01*
G01X148693Y596771D02*
Y597907D01*
G01D02*
X148240Y598360D01*
G01D02*
X147115D01*
G01X151843Y599921D02*
Y605000D01*
G01D02*
X152343Y605500D01*
G01D02*
X153200D01*
G01D02*
X153554Y605146D01*
G01D02*
Y598800D01*
G01D02*
X153101Y598347D01*
G01D02*
X150269D01*
G01X139244Y612519D02*
X140818Y610945D01*
G01X136095Y593622D02*
X136800D01*
G01D02*
X137300Y593122D01*
G01D02*
Y583316D01*
G01D02*
X136784Y582800D01*
G01D02*
X135021D01*
G01D02*
X134521Y583300D01*
G01D02*
Y595196D01*
G01X142394Y612519D02*
Y612533D01*
G01D02*
X140821Y614106D01*
G01X142394Y599921D02*
X143968Y601495D01*
G01X154992Y612519D02*
Y612521D01*
G01D02*
X156566Y614095D01*
G01X164441Y612519D02*
X165142Y613220D01*
G01X158142Y612519D02*
X158104Y612481D01*
G01D02*
Y608396D01*
G01D02*
X159600Y606900D01*
G01D02*
X166400D01*
G01Y608800D02*
X160900D01*
G01D02*
X159716Y609984D01*
G01D02*
Y610945D01*
G01X132945Y612519D02*
X134520Y610944D01*
G01X136095Y612519D02*
X137669Y610945D01*
G01X142394Y596771D02*
X140956Y595333D01*
G01D02*
Y591675D01*
G01D02*
X140481Y591200D01*
G01D02*
X138975D01*
G01D02*
X138500Y590725D01*
G01D02*
Y589775D01*
G01D02*
X138975Y589300D01*
G01D02*
X140481D01*
G01D02*
X140956Y588825D01*
G01D02*
Y587875D01*
G01D02*
X140481Y587400D01*
G01D02*
X138975D01*
G01D02*
X138500Y586925D01*
G01D02*
Y585975D01*
G01D02*
X138975Y585500D01*
G01D02*
X140481D01*
G01D02*
X140956Y585025D01*
G01D02*
Y584075D01*
G01D02*
X140481Y583600D01*
G01D02*
X138975D01*
G01D02*
X138500Y583125D01*
G01D02*
Y582175D01*
G01D02*
X138975Y581700D01*
G01D02*
X140481D01*
G01D02*
X140956Y581225D01*
G01X132945Y596771D02*
Y595702D01*
G01D02*
X131507Y594264D01*
G01D02*
Y590935D01*
G01D02*
X132907Y589535D01*
G01D02*
Y586000D01*
G01D02*
X131500Y584593D01*
G01D02*
Y584000D01*
G01D02*
Y581542D01*
G01D02*
X132583Y580458D01*
G01D02*
X136757D01*
G01D02*
X136769Y580470D01*
G01X154992Y599921D02*
Y605100D01*
G01D02*
X155492Y605600D01*
G01D02*
X156700D01*
G01D02*
X157200Y605100D01*
G01D02*
Y603500D01*
G01D02*
X157700Y603000D01*
G01D02*
X159216D01*
G01D02*
X159716Y603500D01*
G01D02*
Y604645D01*
G01X158142Y615669D02*
X159716Y614095D01*
G01X164441Y615669D02*
Y616900D01*
G01D02*
X164941Y617400D01*
G01D02*
X168500D01*
G01Y614095D02*
X162867D01*
G01X145543Y615669D02*
X147100Y617226D01*
G01D02*
X150251D01*
G01X136095Y618818D02*
X134603Y617326D01*
G01D02*
X134581D01*
G01D02*
X134521Y617266D01*
G01X132945Y615669D02*
X134519Y614095D01*
G01X148693Y615669D02*
Y615648D01*
G01D02*
X147141Y614096D01*
G01X153700Y740650D02*
X155290Y742240D01*
G01D02*
X161050D01*
G01X153700Y740650D02*
X149649D01*
G01D02*
X149241Y740242D01*
G01X146500Y795750D02*
X148090Y797340D01*
G01D02*
X153850D01*
G01X146500Y795750D02*
X142716D01*
G01D02*
X142492Y795526D01*
G01X196018Y241354D02*
Y249032D01*
G01X171094Y237961D02*
X170673Y237540D01*
G01D02*
X166890D01*
G01X196018Y249032D02*
X193950Y251100D01*
G01X171094Y243961D02*
Y247494D01*
G01D02*
X171100Y247500D01*
G01X182604Y446672D02*
Y442854D01*
G01X197841Y430392D02*
X200785D01*
G01X192733Y461582D02*
X189275Y465040D01*
G01D02*
Y470882D01*
G01X173641Y480649D02*
X178690Y475600D01*
G01D02*
X185600D01*
G01D02*
X189275Y471925D01*
G01D02*
Y470882D01*
G01X177377Y461749D02*
X177138Y461988D01*
G01D02*
Y467624D01*
G01D02*
X165904Y478858D01*
G01D02*
Y482361D01*
G01X168320Y455278D02*
Y462990D01*
G01X180000Y466000D02*
X178702Y467298D01*
G01D02*
Y468298D01*
G01D02*
X167342Y479658D01*
G01X182589Y450747D02*
Y446687D01*
G01D02*
X182604Y446672D01*
G01X184116Y458560D02*
X182521Y456965D01*
G01D02*
Y450815D01*
G01D02*
X182589Y450747D01*
G01X185200Y466000D02*
Y463144D01*
G01D02*
X184116Y462060D01*
G01X185200Y466000D02*
X178996Y472204D01*
G01D02*
X176903D01*
G01D02*
X169053Y480054D01*
G01X172800Y457750D02*
X179328D01*
G01D02*
X179599Y457479D01*
G01X196239Y462262D02*
Y461588D01*
G01D02*
X192733Y458082D01*
G01D02*
X192023D01*
G01D02*
X188150Y461955D01*
G01X172800Y461250D02*
Y467339D01*
G01D02*
X169399Y470740D01*
G01X175000Y466000D02*
Y468500D01*
G01X166515Y471345D02*
Y469453D01*
G01D02*
X170192Y465776D01*
G01X192173Y466075D02*
Y472727D01*
G01D02*
X187800Y477100D01*
G01D02*
X180340D01*
G01D02*
X176791Y480649D01*
G01X165904Y482361D02*
X167342Y483799D01*
G01X179940Y512145D02*
X181395Y513600D01*
G01X173641Y499547D02*
X175215Y497973D01*
G01X170491Y512145D02*
X172065Y510571D01*
G01X167342Y490098D02*
X165768Y488524D01*
G01X167342Y479658D02*
Y480649D01*
G01X169053Y480054D02*
Y482361D01*
G01D02*
X170491Y483799D01*
G01X173641Y512145D02*
X175215Y510571D01*
G01X204423Y504134D02*
X181378D01*
G01D02*
X179940Y502696D01*
G01X173641Y493248D02*
X175215Y491674D01*
G01X176791Y499547D02*
X178365Y497973D01*
G01X199829Y485947D02*
X198629Y487147D01*
G01D02*
X196048D01*
G01D02*
X186798Y496397D01*
G01D02*
X183090D01*
G01X179940D02*
X181378Y497835D01*
G01D02*
X186971D01*
G01D02*
X196199Y488607D01*
G01D02*
X198946D01*
G01X173641Y505846D02*
X175216Y504271D01*
G01X176791Y512145D02*
X178365Y510571D01*
G01X198279Y496230D02*
X199583D01*
G01X198279D02*
X194755D01*
G01D02*
X190000Y500985D01*
G01D02*
X181378D01*
G01D02*
X179940Y499547D01*
G01X198803Y501591D02*
X195420D01*
G01D02*
X194315Y502696D01*
G01D02*
X183090D01*
G01X170491Y508996D02*
X172065Y507422D01*
G01X202696Y479804D02*
X196778Y485722D01*
G01D02*
X196001D01*
G01D02*
X188475Y493248D01*
G01D02*
X183090D01*
G01X176791Y505846D02*
X178365Y504272D01*
G01X167342Y493248D02*
X165768Y491674D01*
G01X189393Y517593D02*
X183945Y512145D01*
G01D02*
X183090D01*
G01X170491Y505846D02*
X172065Y504272D01*
G01X170491Y490098D02*
X172065Y488524D01*
G01X183090Y524744D02*
X183982D01*
G01D02*
X186600Y527362D01*
G01D02*
X202782D01*
G01X181395Y513600D02*
X183684D01*
G01D02*
X190151Y520067D01*
G01D02*
X198567D01*
G01D02*
X199442Y520942D01*
G01X183090Y537342D02*
X185578D01*
G01D02*
X195999Y547763D01*
G01X176791Y543641D02*
X177765D01*
G01D02*
X179377Y545253D01*
G01D02*
X180577D01*
G01D02*
X181552Y546228D01*
G01D02*
Y547428D01*
G01X165904Y547386D02*
Y545353D01*
G01X173641Y543641D02*
X174616D01*
G01D02*
X176228Y545253D01*
G01D02*
X177428D01*
G01D02*
X178402Y546227D01*
G01D02*
Y547446D01*
G01X173641Y527893D02*
X175215Y526319D01*
G01X176791Y531043D02*
X178365Y529469D01*
G01X176791Y534192D02*
X178365Y532618D01*
G01X175079Y547500D02*
Y546196D01*
G01D02*
X173962Y545079D01*
G01D02*
X173046D01*
G01D02*
X171608Y543641D01*
G01D02*
X170491D01*
G01X168780Y547113D02*
Y545079D01*
G01D02*
X167342Y543641D01*
G01X196882Y542190D02*
X204390D01*
G01X196882D02*
X192902D01*
G01D02*
X184904Y534192D01*
G01D02*
X183090D01*
G01X176791Y537342D02*
X178365Y535768D01*
G01X173641Y531043D02*
X175215Y529469D01*
G01X200425Y537075D02*
X191501D01*
G01D02*
X183926Y529500D01*
G01D02*
X181483D01*
G01D02*
X179940Y531043D01*
G01X173641Y537342D02*
X175216Y535767D01*
G01X173641Y515295D02*
X175215Y513721D01*
G01X179940Y534192D02*
X181632Y532500D01*
G01D02*
X184450D01*
G01D02*
X191875Y539925D01*
G01D02*
X201925D01*
G01X198000Y534500D02*
X190164D01*
G01D02*
X183557Y527893D01*
G01D02*
X183090D01*
G01Y531043D02*
X184231D01*
G01D02*
X191688Y538500D01*
G01D02*
X203300D01*
G01X167342Y537342D02*
X168916Y538916D01*
G01X173641Y540492D02*
X175215Y538918D01*
G01X170491Y537342D02*
X172065Y535768D01*
G01X170491Y531043D02*
X172065Y529469D01*
G01X196504Y557570D02*
X184113Y545179D01*
G01D02*
X182453D01*
G01D02*
X180915Y543641D01*
G01D02*
X179940D01*
G01X173641Y524744D02*
X175215Y523170D01*
G01X179940Y537342D02*
X181378Y535904D01*
G01D02*
X185378D01*
G01D02*
X195812Y546338D01*
G01D02*
X200847D01*
G01X183090Y540492D02*
X185474D01*
G01D02*
X197644Y552662D01*
G01X176791Y515295D02*
X178365Y513721D01*
G01X170491Y534192D02*
X172065Y532618D01*
G01X170491Y515295D02*
X172065Y513721D01*
G01X198000Y523000D02*
X183717D01*
G01D02*
X183685Y523032D01*
G01D02*
X181652D01*
G01D02*
X179940Y524744D01*
G01X197095Y556145D02*
X185254Y544304D01*
G01D02*
X183753D01*
G01D02*
X183090Y543641D01*
G01X170491Y527893D02*
X172065Y526319D01*
G01X173641Y534192D02*
X175215Y532618D01*
G01X179940Y540492D02*
X180915D01*
G01D02*
X182526Y542103D01*
G01D02*
X185069D01*
G01D02*
X197466Y554500D01*
G01X198000Y529500D02*
X187500D01*
G01D02*
X184455Y526455D01*
G01D02*
X181378D01*
G01D02*
X179940Y527893D01*
G01X170491Y540492D02*
X172065Y538918D01*
G01X176791Y524744D02*
X178365Y523170D01*
G01X200217Y517593D02*
X189393D01*
G01X176791Y540492D02*
X177765D01*
G01D02*
X179303Y538954D01*
G01D02*
X185613D01*
G01D02*
X196251Y549592D01*
G01X167342Y540492D02*
X168916Y542066D01*
G01X167342Y534192D02*
X168916Y535766D01*
G01X174500Y566500D02*
X177000Y564000D01*
G01D02*
Y554659D01*
G01D02*
X171445Y549104D01*
G01D02*
X169533D01*
G01D02*
X167905Y547476D01*
G01D02*
Y547354D01*
G01D02*
X167342Y546791D01*
G01X195999Y547763D02*
X201438D01*
G01X201500Y568300D02*
X198082Y564882D01*
G01D02*
Y564864D01*
G01D02*
X196782Y563564D01*
G01X181552Y547428D02*
X183124Y549000D01*
G01D02*
X183902D01*
G01D02*
X192976Y558074D01*
G01D02*
X193062D01*
G01D02*
X194772Y559784D01*
G01D02*
Y559870D01*
G01D02*
X195482Y560580D01*
G01D02*
Y562264D01*
G01D02*
X196782Y563564D01*
G01X174500Y561500D02*
Y553397D01*
G01D02*
X171082Y549979D01*
G01D02*
X168497D01*
G01D02*
X165904Y547386D01*
G01X178402Y547446D02*
X191922Y560966D01*
G01D02*
Y564138D01*
G01D02*
X194839Y567055D01*
G01D02*
Y577651D01*
G01D02*
X193610Y578880D01*
G01X189500Y567700D02*
Y570750D01*
G01X176791Y546791D02*
Y548000D01*
G01D02*
X186925Y558134D01*
G01D02*
Y562625D01*
G01D02*
X189500Y565200D01*
G01D02*
Y567700D01*
G01X172362Y555082D02*
Y581862D01*
G01X185500Y567700D02*
Y570750D01*
G01Y567700D02*
X186340Y566860D01*
G01D02*
Y564056D01*
G01D02*
X185500Y563216D01*
G01D02*
Y557947D01*
G01D02*
X175916Y548363D01*
G01D02*
Y548337D01*
G01D02*
X175079Y547500D01*
G01X175360Y580890D02*
X173787Y579317D01*
G01D02*
Y570237D01*
G01D02*
X178425Y565599D01*
G01D02*
Y554846D01*
G01D02*
X171808Y548229D01*
G01D02*
X169896D01*
G01D02*
X168780Y547113D01*
G01X178500Y576376D02*
X181275Y573601D01*
G01D02*
Y555134D01*
G01D02*
X173641Y547500D01*
G01D02*
Y546791D01*
G01X199144Y562226D02*
X196197Y559279D01*
G01D02*
Y559193D01*
G01D02*
X195078Y558074D01*
G01D02*
X194992D01*
G01D02*
X183709Y546791D01*
G01D02*
X183090D01*
G01X176500Y571500D02*
X179850Y568150D01*
G01D02*
Y555033D01*
G01D02*
X171608Y546791D01*
G01D02*
X170491D01*
G01X197500Y570282D02*
Y567490D01*
G01D02*
X197334Y567324D01*
G01D02*
Y567232D01*
G01D02*
X193347Y563245D01*
G01D02*
Y560375D01*
G01D02*
X191046Y558074D01*
G01D02*
X190960D01*
G01D02*
X179940Y547054D01*
G01D02*
Y546791D01*
G01X202300Y559763D02*
X198697D01*
G01D02*
X197622Y558688D01*
G01D02*
Y558602D01*
G01D02*
X196590Y557570D01*
G01D02*
X196504D01*
G01X197644Y552662D02*
X204862D01*
G01X204283Y557500D02*
X198536D01*
G01D02*
X197181Y556145D01*
G01D02*
X197095D01*
G01X197466Y554500D02*
X203271D01*
G01X196251Y549592D02*
X196886D01*
G01D02*
X197763Y550469D01*
G01D02*
X199879D01*
G01X166652Y599883D02*
X167936Y598600D01*
G01D02*
X174500D01*
G01D02*
X175000Y599100D01*
G01D02*
Y606300D01*
G01D02*
X174500Y606800D01*
G01D02*
X172900D01*
G01D02*
X172400Y606300D01*
G01D02*
Y602555D01*
G01D02*
X171895Y602050D01*
G01D02*
X166570D01*
G01D02*
X166016Y601496D01*
G01X177187Y585000D02*
Y586239D01*
G01Y585000D02*
X181000D01*
G01X172362Y581862D02*
X175500Y585000D01*
G01D02*
X177187D01*
G01X195500Y598250D02*
X196000Y597750D01*
G01D02*
X199750D01*
G01X195500Y598250D02*
X191500D01*
G01X175360Y580890D02*
X176810Y582340D01*
G01D02*
X180160D01*
G01D02*
X181000Y581500D01*
G01X191500Y586750D02*
X189750D01*
G01D02*
X187750Y584750D01*
G01X191500Y586750D02*
X195500D01*
G01D02*
X200250D01*
G01X191500Y594250D02*
X189250D01*
G01D02*
X187500Y596000D01*
G01X191500Y594250D02*
X195500D01*
G01D02*
X198250D01*
G01D02*
X200720Y591780D01*
G01X165142Y613220D02*
X170200D01*
G01D02*
X170600Y613620D01*
G01D02*
Y615000D01*
G01X173300Y615200D02*
Y610400D01*
G01D02*
X172800Y609900D01*
G01D02*
X166516D01*
G01D02*
X166016Y610400D01*
G01D02*
Y610944D01*
G01X166400Y606900D02*
X166900Y607400D01*
G01D02*
Y608300D01*
G01D02*
X166400Y608800D01*
G01X168500Y617400D02*
X169000Y616900D01*
G01D02*
Y614595D01*
G01D02*
X168500Y614095D01*
G01X170600Y615000D02*
X171200Y615600D01*
G01D02*
X172900D01*
G01D02*
X173300Y615200D01*
G01X186000Y716750D02*
X187590Y718340D01*
G01D02*
X193350D01*
G01X186000Y716750D02*
X182093D01*
G01D02*
X181873Y716530D01*
G01X189913Y736842D02*
X189221Y736150D01*
G01D02*
X184700D01*
G01D02*
X183110Y734560D01*
G01D02*
X177350D01*
G01X186000Y772250D02*
X185508Y771758D01*
G01D02*
X182092D01*
G01X186000Y772250D02*
X187590Y773840D01*
G01D02*
X193350D01*
G01X177500Y791250D02*
X175910Y789660D01*
G01D02*
X170150D01*
G01X177500Y791250D02*
X177894Y791644D01*
G01D02*
Y800059D01*
G01D02*
X177092Y800861D01*
G01X216461Y111992D02*
X221080Y107373D01*
G01D02*
X227070D01*
G01D02*
X227738Y106705D01*
G01D02*
Y104836D01*
G01D02*
X228985Y103589D01*
G01D02*
X235713D01*
G01Y93589D02*
X228163D01*
G01X235713Y88589D02*
X228163D01*
G01X222356Y133438D02*
Y128757D01*
G01D02*
X218756Y125157D01*
G01D02*
X217538D01*
G01D02*
X216461Y124080D01*
G01D02*
Y111992D01*
G01X213607Y130425D02*
X219175D01*
G01D02*
X220300Y129300D01*
G01X224600Y120050D02*
Y116880D01*
G01D02*
X224576Y116678D01*
G01X206107Y134300D02*
X203740Y136667D01*
G01D02*
Y144334D01*
G01X224900Y109350D02*
X221702D01*
G01D02*
X221418Y109634D01*
G01X207369Y147734D02*
X205744D01*
G01D02*
X203740Y145730D01*
G01D02*
Y144334D01*
G01X207699Y143587D02*
Y147404D01*
G01D02*
X207369Y147734D01*
G01X218979Y145011D02*
X216495Y147841D01*
G01D02*
X214145D01*
G01X211199Y143587D02*
Y147121D01*
G01D02*
X211919Y147841D01*
G01D02*
X214145D01*
G01X201018Y209858D02*
Y200568D01*
G01D02*
X200300Y199850D01*
G01X222200Y300500D02*
X232700Y290000D01*
G01X220969Y434922D02*
Y431372D01*
G01X215338Y433845D02*
X217882D01*
G01D02*
X218959Y434922D01*
G01D02*
X220969D01*
G01X235750Y431850D02*
X230738Y436862D01*
G01D02*
Y449662D01*
G01X202652Y432259D02*
X204238Y433845D01*
G01D02*
X207938D01*
G01X200785Y430392D02*
X202652Y432259D01*
G01X230738Y449662D02*
X228700Y451700D01*
G01D02*
Y456800D01*
G01D02*
X231812Y459912D01*
G01D02*
Y480388D01*
G01X209750Y482000D02*
Y478000D01*
G01D02*
Y473750D01*
G01D02*
X210000Y473500D01*
G01X228900Y446800D02*
X226700Y449000D01*
G01D02*
Y456816D01*
G01D02*
X230387Y460503D01*
G01D02*
Y478813D01*
G01D02*
X225800Y483400D01*
G01X220253Y498347D02*
X221152Y499246D01*
G01X220253Y498347D02*
X218438Y500162D01*
G01D02*
X208395D01*
G01D02*
X204423Y504134D01*
G01X223912Y495300D02*
X223300D01*
G01D02*
X220253Y498347D01*
G01X231812Y480388D02*
X230500Y481700D01*
G01D02*
Y494300D01*
G01D02*
X229500Y495300D01*
G01D02*
X227412D01*
G01X199829Y485947D02*
X201254Y484522D01*
G01D02*
X203550D01*
G01D02*
X205028Y486000D01*
G01D02*
X209750D01*
G01Y490000D02*
X204500D01*
G01D02*
X203500D01*
G01D02*
X202922Y490578D01*
G01D02*
X200917D01*
G01X198946Y488607D02*
X200917Y490578D01*
G01X203500Y499125D02*
X204799Y497826D01*
G01D02*
Y496600D01*
G01D02*
X205561Y495838D01*
G01D02*
X208412D01*
G01D02*
X209850Y494400D01*
G01X203500Y499125D02*
Y499200D01*
G01X199583Y496230D02*
X202613Y499260D01*
G01D02*
X203365D01*
G01D02*
X203500Y499125D01*
G01X198803Y501591D02*
X205728D01*
G01D02*
X208032Y499287D01*
G01D02*
X216954D01*
G01D02*
X222124Y494117D01*
G01D02*
Y492976D01*
G01D02*
X223900Y491200D01*
G01X204700Y479804D02*
Y481630D01*
G01D02*
X207026Y483956D01*
G01X209750Y482000D02*
X207959D01*
G01D02*
X207026Y482933D01*
G01D02*
Y483956D01*
G01X204700Y479804D02*
X202696D01*
G01X225800Y483400D02*
Y488201D01*
G01D02*
X227400Y489801D01*
G01D02*
Y491200D01*
G01X203314Y527894D02*
X205420Y530000D01*
G01D02*
X208000D01*
G01X202782Y527362D02*
X203314Y527894D01*
G01X204200Y522600D02*
X205100D01*
G01D02*
X208000Y525500D01*
G01D02*
X209750D01*
G01X199442Y520942D02*
Y521127D01*
G01D02*
X200753Y522438D01*
G01D02*
X200938D01*
G01D02*
X201100Y522600D01*
G01D02*
X204200D01*
G01X229000Y525750D02*
X232787D01*
G01X225000D02*
X221000D01*
G01X225000D02*
X229000D01*
G01X221000D02*
X220427Y526323D01*
G01D02*
X214073D01*
G01D02*
X213250Y525500D01*
G01X204390Y542190D02*
X206700Y544500D01*
G01D02*
X208700Y542500D01*
G01D02*
X209750D01*
G01X203000Y534500D02*
X200425Y537075D01*
G01X206700Y538500D02*
X209750D01*
G01X201925Y539925D02*
X202338Y540338D01*
G01D02*
X204862D01*
G01D02*
X206700Y538500D01*
G01X203300D02*
X207300Y534500D01*
G01D02*
X209750D01*
G01X217163Y523586D02*
X215336D01*
G01D02*
X213250Y521500D01*
G01X225000Y521850D02*
X229000D01*
G01X225000D02*
X224900Y521750D01*
G01D02*
X221000D01*
G01D02*
X219164Y523586D01*
G01D02*
X217163D01*
G01X200847Y546338D02*
X202685Y544500D01*
G01D02*
X203300D01*
G01X200217Y517593D02*
X200395D01*
G01D02*
X202589Y519787D01*
G01D02*
X205787D01*
G01D02*
X207500Y521500D01*
G01D02*
X209750D01*
G01X206700Y548500D02*
X207750D01*
G01D02*
X209750Y550500D01*
G01X201438Y547763D02*
X202539Y546662D01*
G01D02*
X204162D01*
G01D02*
X206000Y548500D01*
G01D02*
X206700D01*
G01X201500Y570282D02*
Y568300D01*
G01X222622Y563994D02*
X217140D01*
G01D02*
X216241Y563095D01*
G01X205500Y574250D02*
X207338Y572412D01*
G01D02*
Y564662D01*
G01D02*
X208500Y563500D01*
G01X202610Y563580D02*
X205500Y566470D01*
G01D02*
Y570750D01*
G01X202610Y563580D02*
X201256Y562226D01*
G01D02*
X199144D01*
G01X202300Y559763D02*
X202763D01*
G01D02*
X204601Y561601D01*
G01D02*
X206461D01*
G01D02*
X206700Y561362D01*
G01D02*
X209385D01*
G01D02*
X211062Y563039D01*
G01D02*
Y569188D01*
G01D02*
X209750Y570500D01*
G01X204862Y552662D02*
X206700Y554500D01*
G01X205700Y559763D02*
Y558917D01*
G01D02*
X204283Y557500D01*
G01X203271Y554500D02*
X203447Y554676D01*
G01D02*
Y554684D01*
G01D02*
X203304D01*
G01X222500Y573220D02*
X223308Y572412D01*
G01D02*
X226200D01*
G01D02*
Y570600D01*
G01D02*
X226120Y570520D01*
G01D02*
Y568020D01*
G01X230856Y566468D02*
X229304Y568020D01*
G01D02*
X226120D01*
G01X226122Y563994D02*
X229605D01*
G01D02*
X230856Y565245D01*
G01D02*
Y566468D01*
G01X203300Y548500D02*
X203750D01*
G01D02*
X209750Y554500D01*
G01X200000Y550424D02*
X201376D01*
G01D02*
X203300Y548500D01*
G01X199879Y550469D02*
X199924Y550424D01*
G01D02*
X200000D01*
G01X204100Y600100D02*
X204910Y599290D01*
G01D02*
Y594340D01*
G01X199750Y597750D02*
X202100Y600100D01*
G01D02*
X204100D01*
G01X200250Y586750D02*
X202720Y589220D01*
G01D02*
X204910D01*
G01X200720Y591780D02*
X204910D01*
G01X223500Y601500D02*
Y596673D01*
G01D02*
X224828Y595345D01*
G01D02*
Y592108D01*
G01D02*
X224500Y591780D01*
G01D02*
X221090D01*
G01X217000Y712250D02*
X215410Y710660D01*
G01D02*
X209650D01*
G01X217000Y712250D02*
X221200D01*
G01X217000Y767750D02*
X215410Y766160D01*
G01D02*
X209650D01*
G01X217000Y767750D02*
X218078Y768828D01*
G01D02*
Y771405D01*
G01D02*
X218080Y771407D01*
G01X250181Y93589D02*
X258100D01*
G01X264443Y109587D02*
X262346Y107490D01*
G01D02*
X259118D01*
G01D02*
X255217Y103589D01*
G01D02*
X250181D01*
G01Y88589D02*
X257961D01*
G01D02*
X260562Y85988D01*
G01X253978Y124804D02*
X254410D01*
G01D02*
X257422Y121792D01*
G01X235713Y118589D02*
Y121213D01*
G01D02*
X239304Y124804D01*
G01D02*
X250478D01*
G01D02*
Y129381D01*
G01D02*
X248992Y130867D01*
G01X236250Y139500D02*
X236000D01*
G01D02*
X233500Y137000D01*
G01X259331Y118580D02*
X259194D01*
G01D02*
X259185Y118589D01*
G01D02*
X250181D01*
G01X236231Y245001D02*
Y233930D01*
G01D02*
X236331Y233830D01*
G01D02*
X240380D01*
G01D02*
X240400Y233850D01*
G01X258900Y297050D02*
X245950D01*
G01D02*
X245400Y296500D01*
G01X267137Y313438D02*
X258900Y305201D01*
G01D02*
Y297050D01*
G01X232700Y290000D02*
X240700D01*
G01D02*
X241231Y289469D01*
G01D02*
Y283559D01*
G01X263000Y293350D02*
X262800Y293550D01*
G01D02*
X258900D01*
G01X261231Y283559D02*
Y288331D01*
G01D02*
X263000Y290100D01*
G01D02*
Y293350D01*
G01X263068Y328619D02*
X265235Y326452D01*
G01D02*
X286752D01*
G01X261479Y334140D02*
Y330208D01*
G01D02*
X263068Y328619D01*
G01X252250Y343500D02*
Y344150D01*
G01D02*
X249800Y346600D01*
G01X251850Y339700D02*
X252250Y340100D01*
G01D02*
Y343500D01*
G01X273229Y338640D02*
X264979D01*
G01X266600Y331300D02*
X264979Y332921D01*
G01D02*
Y334140D01*
G01D02*
Y338640D01*
G01X274702Y365240D02*
X263493D01*
G01D02*
X257200Y358947D01*
G01D02*
Y353960D01*
G01D02*
X262760D01*
G01D02*
X266190Y357390D01*
G01D02*
X266729D01*
G01X262604Y350015D02*
X266729Y345890D01*
G01X257200Y351400D02*
X261219D01*
G01D02*
X262604Y350015D01*
G01X249800Y346600D02*
Y348840D01*
G01D02*
X244760D01*
G01D02*
X244400Y349200D01*
G01D02*
Y350925D01*
G01D02*
X244875Y351400D01*
G01D02*
X249800D01*
G01X262900Y430350D02*
X265557D01*
G01D02*
X266756Y431549D01*
G01X262900Y430350D02*
X262650Y430600D01*
G01D02*
X257600D01*
G01X238400Y416200D02*
X237700Y416900D01*
G01D02*
Y436800D01*
G01D02*
X235500Y439000D01*
G01X235750Y419500D02*
Y431850D01*
G01X244900Y430850D02*
Y429400D01*
G01D02*
X241800Y426300D01*
G01X250200Y430600D02*
X245150D01*
G01D02*
X244900Y430850D01*
G01X265800Y467660D02*
X266160Y467300D01*
G01D02*
X269350D01*
G01X266523Y469500D02*
X265800Y468777D01*
G01D02*
Y467660D01*
G01X235500Y459000D02*
X236500D01*
G01D02*
X242575Y465075D01*
G01D02*
Y492575D01*
G01X235500Y449000D02*
X237800D01*
G01D02*
X244000Y455200D01*
G01D02*
Y491900D01*
G01X241150Y493836D02*
Y473650D01*
G01D02*
X236500Y469000D01*
G01D02*
X235500D01*
G01X239725Y482225D02*
X236500Y479000D01*
G01D02*
X235500D01*
G01X242575Y492575D02*
X246800Y496800D01*
G01X244000Y491900D02*
X245500Y493400D01*
G01D02*
X246500D01*
G01X233290Y493277D02*
X235500Y491067D01*
G01D02*
Y489000D01*
G01X242800Y495486D02*
X241150Y493836D01*
G01X240450Y499400D02*
X240400D01*
G01D02*
Y497227D01*
G01D02*
X239725Y496552D01*
G01D02*
Y482225D01*
G01X236737Y493170D02*
Y494306D01*
G01D02*
X235500Y495543D01*
G01D02*
Y499000D01*
G01X265800Y485000D02*
X266600Y485800D01*
G01X269100Y481283D02*
X265800Y484583D01*
G01D02*
Y485000D01*
G01X239321Y521081D02*
X238684Y520444D01*
G01D02*
X236173D01*
G01D02*
X235291Y521326D01*
G01D02*
Y522208D01*
G01D02*
X236130Y523047D01*
G01D02*
X241648D01*
G01D02*
X242500Y522195D01*
G01D02*
Y521250D01*
G01X232787Y525750D02*
X233101Y526064D01*
G01X239139Y525077D02*
X238023D01*
G01D02*
X236800Y526300D01*
G01D02*
Y527701D01*
G01D02*
X237779Y528680D01*
G01D02*
X238931D01*
G01D02*
X241861Y525750D01*
G01D02*
X242500D01*
G01X249674Y532413D02*
X248213D01*
G01D02*
X246500Y530700D01*
G01D02*
Y529250D01*
G01X253500D02*
Y529500D01*
G01D02*
X250587Y532413D01*
G01D02*
X249674D01*
G01X257500Y529250D02*
X253500D01*
G01X242500D02*
X246500D01*
G01X249601Y514174D02*
X252345D01*
G01D02*
X253500Y515329D01*
G01D02*
Y517750D01*
G01X249601Y514174D02*
X247099D01*
G01D02*
X246500Y514773D01*
G01D02*
Y517750D01*
G01X242500D02*
X246500D01*
G01X258000D02*
X253500D01*
G01X257000Y585500D02*
X255770Y584270D01*
G01D02*
Y581381D01*
G01X263488Y583165D02*
X261335D01*
G01D02*
X259000Y585500D01*
G01D02*
X257000D01*
G01X273550Y635900D02*
X265400D01*
G01X260800Y651900D02*
X256900D01*
G01D02*
X256600Y652200D01*
G01X257500Y725500D02*
Y713982D01*
G01D02*
X274408Y697074D01*
G01X252749Y779681D02*
Y712456D01*
G01D02*
X272780Y692425D01*
G01X271800Y691000D02*
X251324Y711476D01*
G01D02*
Y780272D01*
G01X273760Y693850D02*
X254175Y713435D01*
G01D02*
Y779091D01*
G01X258100Y726100D02*
X257500Y725500D01*
G01X255600Y778500D02*
Y728600D01*
G01D02*
X258100Y726100D01*
G01X269239Y730812D02*
X262600Y737451D01*
G01D02*
X262628Y737479D01*
G01D02*
Y744470D01*
G01X241700Y873496D02*
Y738800D01*
G01D02*
X243000Y737500D01*
G01X241000Y721500D02*
X243000Y723500D01*
G01D02*
Y737500D01*
G01X241000Y725500D02*
X240275Y726225D01*
G01D02*
Y731000D01*
G01Y874279D02*
Y731000D01*
G01X246000Y756788D02*
Y745500D01*
G01X241000Y718000D02*
X241500D01*
G01D02*
X246000Y722500D01*
G01D02*
Y745500D01*
G01X260000Y782900D02*
X255600Y778500D01*
G01X260168Y787100D02*
X252749Y779681D01*
G01X251324Y780272D02*
X259852Y788800D01*
G01X254175Y779091D02*
X260484Y785400D01*
G01X244488Y887970D02*
Y758300D01*
G01D02*
X246000Y756788D01*
G01X283350Y782900D02*
X260000D01*
G01X289805Y787100D02*
X260168D01*
G01X259852Y788800D02*
X290510D01*
G01X260484Y785400D02*
X289100D01*
G01X241339Y887970D02*
Y881861D01*
G01D02*
X241700Y881500D01*
G01D02*
Y880955D01*
G01D02*
X243027Y879628D01*
G01D02*
Y874823D01*
G01D02*
X241700Y873496D01*
G01X238189Y887970D02*
Y882450D01*
G01D02*
X241602Y879037D01*
G01D02*
Y875606D01*
G01D02*
X240275Y874279D01*
G01X278909Y141324D02*
X280176D01*
G01D02*
X281500Y140000D01*
G01D02*
Y137250D01*
G01X277500D02*
Y139915D01*
G01D02*
X278909Y141324D01*
G01X277500Y137250D02*
X274751D01*
G01D02*
X272900Y139101D01*
G01D02*
Y142600D01*
G01X284440Y139580D02*
X280620Y143400D01*
G01X346569Y139262D02*
X284758D01*
G01D02*
X284440Y139580D01*
G01X272900Y142600D02*
X271374Y144126D01*
G01D02*
X269143D01*
G01X280620Y143400D02*
X279850D01*
G01D02*
X277750Y145500D01*
G01X269143Y146094D02*
X273518D01*
G01D02*
X273950Y145662D01*
G01D02*
X277588D01*
G01D02*
X277750Y145500D01*
G01X281100Y205050D02*
X290350D01*
G01D02*
X292500Y207200D01*
G01X272900Y293250D02*
X272800Y293150D01*
G01D02*
Y290300D01*
G01D02*
X271231Y288731D01*
G01D02*
Y283559D01*
G01X304451Y330463D02*
X297537D01*
G01D02*
X296700Y331300D01*
G01D02*
X288800D01*
G01D02*
X286460Y333640D01*
G01D02*
X273229D01*
G01X301679Y309360D02*
X297601Y313438D01*
G01D02*
X267137D01*
G01X286752Y326452D02*
X287102Y326802D01*
G01D02*
X287200D01*
G01X304100Y336350D02*
X299838D01*
G01D02*
X299639Y336151D01*
G01X293229Y333640D02*
X297128D01*
G01D02*
X299639Y336151D01*
G01X300300Y340501D02*
X298500D01*
G01D02*
X296639Y338640D01*
G01D02*
X293229D01*
G01D02*
X283360D01*
G01D02*
X278360Y343640D01*
G01D02*
X273229D01*
G01D02*
Y345671D01*
G01X299296Y327204D02*
X297860Y328640D01*
G01D02*
X293229D01*
G01D02*
X284960D01*
G01D02*
X282300Y331300D01*
G01D02*
X266600D01*
G01X300299Y326201D02*
X299296Y327204D01*
G01X272979Y354640D02*
X270229Y357390D01*
G01D02*
X266729D01*
G01X288270Y365240D02*
X274702D01*
G01X266729Y353890D02*
Y349390D01*
G01X273229Y345671D02*
X272000Y346900D01*
G01D02*
X269219D01*
G01D02*
X266729Y349390D01*
G01X269100Y472600D02*
Y470800D01*
G01D02*
X267800Y469500D01*
G01D02*
X266523D01*
G01X266600Y485800D02*
X269350D01*
G01X269100Y480000D02*
Y481283D01*
G01X290000Y578165D02*
X283488D01*
G01X294238D02*
X290000D01*
G01X289835Y583165D02*
X283488D01*
G01X294238D02*
X289835D01*
G01Y588165D02*
X283488D01*
G01X294238Y588665D02*
X290335D01*
G01D02*
X289835Y588165D01*
G01X274550Y638900D02*
X273950Y639500D01*
G01D02*
X271500D01*
G01X274550Y638900D02*
Y634900D01*
G01D02*
X273550Y635900D01*
G01X274408Y697074D02*
X343426D01*
G01X272780Y692425D02*
X384120D01*
G01X323397Y702861D02*
X296475D01*
G01D02*
X296000Y703336D01*
G01D02*
Y718054D01*
G01X385100Y691000D02*
X271800D01*
G01X383140Y693850D02*
X273760D01*
G01X298406Y719648D02*
Y706000D01*
G01X290200Y712300D02*
X288500Y714000D01*
G01D02*
Y717742D01*
G01X290338Y715800D02*
Y712438D01*
G01D02*
X290200Y712300D01*
G01X298306Y735298D02*
Y732538D01*
G01D02*
X301310Y729534D01*
G01X282946Y735298D02*
Y732792D01*
G01D02*
X280149Y729995D01*
G01D02*
X279604D01*
G01D02*
X279594Y729985D01*
G01D02*
X278708D01*
G01D02*
X275609Y726886D01*
G01X278406Y723148D02*
Y724089D01*
G01D02*
X275609Y726886D01*
G01X277826Y735298D02*
X275351D01*
G01D02*
X270865Y730812D01*
G01D02*
X269239D01*
G01X294406Y719648D02*
X292568Y721486D01*
G01D02*
Y724485D01*
G01D02*
X290720Y726333D01*
G01X296000Y718054D02*
X294406Y719648D01*
G01X293186Y735298D02*
Y732614D01*
G01D02*
X296132Y729668D01*
G01D02*
Y726171D01*
G01X294406Y723148D02*
Y724445D01*
G01D02*
X296132Y726171D01*
G01X288066Y735298D02*
Y729819D01*
G01D02*
X287278Y729031D01*
G01X286406Y723148D02*
X287278Y724020D01*
G01D02*
Y729031D01*
G01X282406Y723148D02*
X280498Y725056D01*
G01D02*
Y726806D01*
G01D02*
X284768D01*
G01D02*
X285124Y726450D01*
G01D02*
X285333Y726241D01*
G01X285506Y735298D02*
Y729739D01*
G01D02*
X285124Y729357D01*
G01D02*
Y726450D01*
G01X280386Y735298D02*
Y732793D01*
G01D02*
X279003Y731410D01*
G01D02*
X273479D01*
G01D02*
X266980Y724911D01*
G01D02*
Y723854D01*
G01X274406Y723148D02*
X274008Y722750D01*
G01D02*
X268084D01*
G01D02*
X266980Y723854D01*
G01X286406Y719648D02*
Y716531D01*
G01X295746Y735298D02*
Y732499D01*
G01D02*
X298620Y729625D01*
G01D02*
Y728596D01*
G01X298406Y723148D02*
Y728382D01*
G01D02*
X298620Y728596D01*
G01X290406Y723148D02*
X288882Y724672D01*
G01D02*
Y727094D01*
G01D02*
X290478Y728690D01*
G01D02*
X292027D01*
G01D02*
X292831Y729494D01*
G01X290626Y735298D02*
Y731900D01*
G01D02*
X292831Y729695D01*
G01D02*
Y729494D01*
G01X282406Y719648D02*
Y716598D01*
G01X288500Y717742D02*
X290406Y719648D01*
G01X286500Y779750D02*
X283350Y782900D01*
G01X295079Y772100D02*
Y781826D01*
G01D02*
X289805Y787100D01*
G01X286500Y768750D02*
X286750D01*
G01D02*
X288338Y770338D01*
G01D02*
Y774412D01*
G01D02*
X286500Y776250D01*
G01X288066Y757498D02*
Y752566D01*
G01D02*
X287500Y752000D01*
G01D02*
X281500D01*
G01X288066Y757498D02*
Y760800D01*
G01D02*
X287278Y761588D01*
G01D02*
Y765421D01*
G01D02*
X287115Y765584D01*
G01D02*
X286500Y766199D01*
G01D02*
Y768750D01*
G01X273700Y752000D02*
X281500D01*
G01X298306Y757498D02*
Y761006D01*
G01D02*
X302700Y765400D01*
G01X296500Y782810D02*
Y782421D01*
G01D02*
X296504Y782417D01*
G01D02*
Y773903D01*
G01D02*
X298052Y772355D01*
G01D02*
X299148D01*
G01X289100Y785400D02*
X292700Y781800D01*
G01D02*
Y777200D01*
G01D02*
X291000Y775500D01*
G01D02*
Y772150D01*
G01X285506Y757498D02*
Y760794D01*
G01D02*
X283500Y762800D01*
G01D02*
Y765631D01*
G01X282478Y768681D02*
X283500Y767659D01*
G01D02*
Y765631D01*
G01X293186Y757498D02*
Y765065D01*
G01D02*
X293692Y765571D01*
G01X295079Y768600D02*
Y766958D01*
G01D02*
X293692Y765571D01*
G01X291000Y768650D02*
Y764272D01*
G01D02*
X290400Y763672D01*
G01X290626Y757498D02*
Y763446D01*
G01D02*
X290400Y763672D01*
G01X299148Y768855D02*
Y765727D01*
G01D02*
X299184Y765691D01*
G01D02*
X296500Y763007D01*
G01D02*
Y763000D01*
G01X295746Y757498D02*
Y762246D01*
G01D02*
X296500Y763000D01*
G01X290510Y788800D02*
X296500Y782810D01*
G01X294000Y865700D02*
Y830000D01*
G01D02*
X295592Y828408D01*
G01X333263Y790737D02*
X295592Y828408D01*
G01X331838Y786662D02*
X296872Y821628D01*
G01X292000Y865684D02*
Y826500D01*
G01D02*
X296872Y821628D01*
G01X288583Y884093D02*
X285170Y880680D01*
G01D02*
Y874530D01*
G01D02*
X294000Y865700D01*
G01X285433Y887970D02*
Y883023D01*
G01D02*
X283745Y881335D01*
G01D02*
Y873939D01*
G01D02*
X292000Y865684D01*
G01X288583Y887970D02*
Y884093D01*
G01X314750Y209450D02*
X312500Y207200D01*
G01X314750Y221900D02*
Y209450D01*
G01X306900Y251000D02*
Y270600D01*
G01D02*
X307834Y271534D01*
G01D02*
Y282786D01*
G01X302834Y245636D02*
Y250366D01*
G01D02*
X302400Y250800D01*
G01D02*
Y251500D01*
G01D02*
X302500Y251600D01*
G01X316646Y297025D02*
X313046D01*
G01D02*
X301679Y308392D01*
G01D02*
Y309360D01*
G01X316646Y293525D02*
X320647D01*
G01D02*
X320662Y293540D01*
G01D02*
X327834Y286368D01*
G01D02*
Y283490D01*
G01X302700Y294512D02*
X302834Y294378D01*
G01D02*
Y283490D01*
G01X307834Y282786D02*
Y283490D01*
G01X306800Y290500D02*
Y291318D01*
G01D02*
X309032Y293550D01*
G01X306800Y290500D02*
X307359D01*
G01D02*
X307834Y290025D01*
G01D02*
Y283490D01*
G01X329000Y320600D02*
Y320100D01*
G01D02*
X330200Y318900D01*
G01D02*
X333050D01*
G01X336141Y323975D02*
X331375D01*
G01D02*
X329000Y321600D01*
G01D02*
Y320600D01*
G01X315300Y337250D02*
Y336410D01*
G01D02*
X312430Y333540D01*
G01D02*
X311440Y332550D01*
G01D02*
X308300D01*
G01D02*
X306538D01*
G01D02*
X304451Y330463D01*
G01X308300Y336050D02*
X308000Y336350D01*
G01D02*
X304100D01*
G01D02*
Y336301D01*
G01X328800Y315900D02*
X323700Y321000D01*
G01D02*
Y343100D01*
G01D02*
X314485Y352315D01*
G01X304839Y340501D02*
X300300D01*
G01X304639Y326201D02*
X300299D01*
G01X314485Y352315D02*
X308310Y358490D01*
G01D02*
X301929D01*
G01X315750Y534500D02*
X313450Y532200D01*
G01D02*
X310000D01*
G01D02*
X306900Y529100D01*
G01X315750Y534500D02*
Y538200D01*
G01D02*
X315650Y538300D01*
G01Y542500D02*
Y538300D01*
G01X306500Y712400D02*
X306406Y712494D01*
G01D02*
Y719648D01*
G01Y706031D02*
X306500Y706125D01*
G01D02*
Y712400D01*
G01X331800Y727268D02*
Y711264D01*
G01D02*
X323397Y702861D01*
G01X302438Y716416D02*
Y714810D01*
G01D02*
X302406Y714778D01*
G01D02*
Y706031D01*
G01X301310Y729534D02*
Y726403D01*
G01X302406Y723148D02*
Y724833D01*
G01D02*
X301310Y725929D01*
G01D02*
Y726403D01*
G01X325500Y758431D02*
Y729500D01*
G01D02*
X326000Y729000D01*
G01X335850Y731318D02*
X331800Y727268D01*
G01X323600Y717800D02*
X329000Y723200D01*
G01D02*
Y726484D01*
G01D02*
X333263Y730747D01*
G01D02*
Y790737D01*
G01X320000Y718200D02*
Y720300D01*
G01D02*
X331838Y732138D01*
G01D02*
Y786662D01*
G01X302406Y719648D02*
Y716448D01*
G01D02*
X302438Y716416D01*
G01X310406Y719648D02*
X308568Y721486D01*
G01D02*
Y724741D01*
G01D02*
X307278Y726031D01*
G01D02*
Y726198D01*
G01X314500Y723250D02*
X314398Y723148D01*
G01D02*
X310406D01*
G01X303426Y735298D02*
Y732946D01*
G01D02*
X308491Y727881D01*
G01D02*
X314448D01*
G01D02*
X315132Y727197D01*
G01X310406Y723148D02*
Y723858D01*
G01D02*
X313049Y726501D01*
G01D02*
X314436D01*
G01D02*
X315132Y727197D01*
G01X300866Y735298D02*
Y732248D01*
G01D02*
X304416Y728698D01*
G01X306406Y723148D02*
X304500Y725054D01*
G01D02*
Y728614D01*
G01D02*
X304416Y728698D01*
G01X304000Y779950D02*
X304950Y779000D01*
G01D02*
X326000D01*
G01D02*
X330000Y775000D01*
G01D02*
Y762931D01*
G01D02*
X325500Y758431D01*
G01X300866Y757498D02*
Y760967D01*
G01D02*
X303449Y763550D01*
G01D02*
X306550D01*
G01D02*
X307000Y764000D01*
G01X307406Y768648D02*
Y764406D01*
G01D02*
X307000Y764000D01*
G01X311406Y772148D02*
Y775198D01*
G01X303300Y768550D02*
X305488Y770738D01*
G01D02*
Y774962D01*
G01D02*
X304000Y776450D01*
G01X302700Y765400D02*
X303300Y766000D01*
G01D02*
Y768550D01*
G01X307406Y772148D02*
Y775198D01*
G01X315406Y772148D02*
Y775200D01*
G01X311406Y768648D02*
Y765706D01*
G01D02*
X311200Y765500D01*
G01X303426Y757498D02*
Y760408D01*
G01D02*
X304590Y761572D01*
G01D02*
X309176D01*
G01D02*
X310622Y760126D01*
G01X311200Y765500D02*
Y760704D01*
G01D02*
X310622Y760126D01*
G01X305986Y757498D02*
X307762D01*
G01D02*
X309083Y756177D01*
G01D02*
X311431D01*
G01D02*
X315406Y760152D01*
G01D02*
Y765598D01*
G01Y768648D02*
Y765598D01*
G01X303266Y825234D02*
X335850Y792650D01*
G01X304662Y828638D02*
X337275Y796025D01*
G01X302074Y868924D02*
Y826426D01*
G01D02*
X303266Y825234D01*
G01X304662Y869461D02*
Y828638D01*
G01X304331Y884109D02*
X305280Y883160D01*
G01D02*
Y872130D01*
G01D02*
X302074Y868924D01*
G01X307481Y887970D02*
Y872280D01*
G01D02*
X304662Y869461D01*
G01X304331Y887970D02*
Y884109D01*
G01X372200Y164893D02*
X346569Y139262D01*
G01X422300Y117000D02*
X349999D01*
G01D02*
X345800Y121199D01*
G01D02*
Y134100D01*
G01D02*
X374293Y162593D01*
G01X365300Y217100D02*
X355400Y207200D01*
G01D02*
X346200D01*
G01X335150Y215250D02*
Y208250D01*
G01D02*
X336200Y207200D01*
G01X410900Y217100D02*
X365300D01*
G01X338650Y222000D02*
Y218750D01*
G01D02*
X335150Y215250D01*
G01X349970Y289608D02*
Y256720D01*
G01X345800Y288800D02*
Y256590D01*
G01D02*
X345820Y256570D01*
G01X337410Y292410D02*
X337834Y291986D01*
G01D02*
Y283490D01*
G01D02*
Y282786D01*
G01X348182Y311498D02*
Y291396D01*
G01D02*
X349970Y289608D01*
G01X336550Y312571D02*
Y301865D01*
G01D02*
X339598Y298817D01*
G01D02*
Y295002D01*
G01D02*
X345800Y288800D01*
G01X344550Y318500D02*
Y315130D01*
G01D02*
X344836Y314844D01*
G01D02*
X348182Y311498D01*
G01X353000Y320300D02*
Y322000D01*
G01D02*
X351025Y323975D01*
G01D02*
X345341D01*
G01X348050Y318500D02*
X352600D01*
G01D02*
X353000Y318900D01*
G01D02*
Y320300D01*
G01X354500Y325200D02*
X354725D01*
G01D02*
X355200Y325675D01*
G01D02*
Y328750D01*
G01X345341Y325945D02*
X351500D01*
G01D02*
X352245Y325200D01*
G01D02*
X354500D01*
G01X339149Y315170D02*
X336550Y312571D01*
G01Y318900D02*
Y317769D01*
G01D02*
X339149Y315170D01*
G01X350050Y718650D02*
X363500Y705200D01*
G01D02*
Y704000D01*
G01X352900Y727200D02*
X370500Y709600D01*
G01X343426Y697074D02*
X344200Y696300D01*
G01X351475Y724425D02*
X367000Y708900D01*
G01D02*
Y704000D01*
G01X337275Y727525D02*
X360000Y704800D01*
G01D02*
Y704000D01*
G01X348900Y730900D02*
X350050Y729750D01*
G01D02*
Y718650D01*
G01Y786678D02*
Y732050D01*
G01D02*
X348900Y730900D01*
G01X352900Y785496D02*
Y727200D01*
G01X335850Y792650D02*
Y731318D01*
G01X351475Y786087D02*
Y724425D01*
G01X337275Y796025D02*
Y727525D01*
G01X372950Y809578D02*
X350050Y786678D01*
G01X375800Y808396D02*
X352900Y785496D01*
G01X374375Y808987D02*
X351475Y786087D01*
G01X372200Y194399D02*
Y164893D01*
G01X374293Y162593D02*
Y193893D01*
G01X387939Y210138D02*
X372200Y194399D01*
G01X374293Y193893D02*
X383600Y203200D01*
G01X446186Y210138D02*
X387939D01*
G01X368900Y315700D02*
X371415Y313185D01*
G01D02*
X431525D01*
G01X370500Y709600D02*
Y705500D01*
G01X384120Y692425D02*
X439595Y747900D01*
G01X440300Y746200D02*
X385100Y691000D01*
G01X438890Y749600D02*
X383140Y693850D01*
G01X372950Y879582D02*
Y809578D01*
G01X375800Y878400D02*
Y808396D01*
G01X374375Y878991D02*
Y808987D01*
G01X373622Y887970D02*
Y880254D01*
G01D02*
X372950Y879582D01*
G01X379922Y887970D02*
Y882522D01*
G01D02*
X375800Y878400D01*
G01X376772Y887970D02*
Y881388D01*
G01D02*
X374375Y878991D01*
G01X436350Y102950D02*
X422300Y117000D01*
G01X431525Y313185D02*
X470970Y352630D01*
G01X466000Y68950D02*
X470200D01*
G01X461440Y74260D02*
X461900Y73800D01*
G01D02*
Y68950D01*
G01D02*
X457700D01*
G01X466560Y106800D02*
Y110482D01*
G01X464000Y84600D02*
Y80000D01*
G01D02*
X470200Y73800D01*
G01X455800Y102950D02*
X436350D01*
G01X455800D02*
Y98950D01*
G01Y95450D02*
Y91100D01*
G01D02*
X455300Y90600D01*
G01X469120Y89705D02*
X463375Y95450D01*
G01D02*
X455800D01*
G01X461440Y84600D02*
Y74260D01*
G01X466560Y84600D02*
Y80440D01*
G01D02*
X470500Y76500D01*
G01X464000Y106800D02*
Y113371D01*
G01X466560Y110482D02*
X470047Y113969D01*
G01Y115736D02*
X466905Y118878D01*
G01X479472Y134047D02*
X466838D01*
G01D02*
X464518Y136367D01*
G01D02*
Y142250D01*
G01X474362Y130750D02*
X466188D01*
G01D02*
X465270Y129832D01*
G01X464000Y113371D02*
X464692Y114063D01*
G01D02*
Y117050D01*
G01D02*
X462868Y118874D01*
G01X464518Y142250D02*
X461009Y145759D01*
G01D02*
X460785D01*
G01X455328Y159738D02*
X458181D01*
G01D02*
X464660Y153259D01*
G01X469910Y143008D02*
X468348D01*
G01D02*
X465219Y146137D01*
G01D02*
Y152700D01*
G01D02*
X464660Y153259D01*
G01X477466Y182770D02*
X467575D01*
G01D02*
X465485Y180680D01*
G01Y200680D02*
Y209103D01*
G01D02*
X463599Y210989D01*
G01X486097Y216594D02*
X452642D01*
G01D02*
X446186Y210138D01*
G01X462700Y380550D02*
X464290Y382140D01*
G01D02*
X470050D01*
G01X458029Y380305D02*
X458034Y380300D01*
G01D02*
X462450D01*
G01D02*
X462700Y380550D01*
G01X439595Y747900D02*
X597700D01*
G01X599200Y746200D02*
X440300D01*
G01X596300Y749600D02*
X438890D01*
G01X505500Y25500D02*
X497488Y17488D01*
G01D02*
Y7874D01*
G01X486720Y26720D02*
Y30990D01*
G01D02*
X486750Y31020D01*
G01X491488Y31496D02*
X487226D01*
G01D02*
X486750Y31020D01*
G01X486979Y8837D02*
X487942Y7874D01*
G01D02*
X491488D01*
G01X486710Y13180D02*
Y9106D01*
G01D02*
X486979Y8837D01*
G01X497488Y42488D02*
Y31496D01*
G01X470200Y68950D02*
Y73800D01*
G01X491488Y55118D02*
X487298D01*
G01D02*
X486760Y54580D01*
G01X486750Y49880D02*
Y54570D01*
G01D02*
X486760Y54580D01*
G01X501000Y106388D02*
Y58630D01*
G01D02*
X497488Y55118D01*
G01X486734Y78047D02*
Y73396D01*
G01D02*
X486750Y73380D01*
G01X502425Y47425D02*
X497488Y42488D01*
G01X475700Y76500D02*
X478400Y73800D01*
G01Y68950D02*
X474400D01*
G01X478400D02*
Y73800D01*
G01X469120Y109221D02*
Y106800D01*
G01X483787Y123601D02*
X501000Y106388D01*
G01X486764Y78077D02*
X486734Y78047D01*
G01X491488Y78740D02*
X487427D01*
G01D02*
X486764Y78077D01*
G01X474622Y130750D02*
X497488Y107884D01*
G01D02*
Y78740D01*
G01X469120Y84600D02*
Y89705D01*
G01X470500Y76500D02*
X475700D01*
G01X475567Y136564D02*
X480881D01*
G01X469145Y137332D02*
X469913Y136564D01*
G01D02*
X475567D01*
G01X470047Y113969D02*
Y115736D01*
G01X478800Y119250D02*
Y116899D01*
G01D02*
X476553Y114652D01*
G01D02*
X475089D01*
G01D02*
X474551D01*
G01D02*
X469120Y109221D01*
G01X480881Y140064D02*
Y142480D01*
G01X497530Y144850D02*
X493500Y140820D01*
G01D02*
Y119980D01*
G01D02*
X505500Y107980D01*
G01X481800Y131719D02*
X483787Y129732D01*
G01D02*
Y123601D01*
G01X481800Y131719D02*
X479472Y134047D01*
G01X474362Y130750D02*
X474622D01*
G01X488838Y145077D02*
Y140700D01*
G01D02*
Y121372D01*
G01D02*
X502425Y107785D01*
G01X480881Y142480D02*
X482800Y144399D01*
G01D02*
Y161900D01*
G01D02*
X480910Y163790D01*
G01D02*
Y164099D01*
G01X498903Y168642D02*
X498900Y168645D01*
G01D02*
Y171800D01*
G01X499278Y159142D02*
Y164767D01*
G01D02*
X498903Y165142D01*
G01X497530Y144850D02*
X504430Y151750D01*
G01X495403Y151642D02*
X488838Y145077D01*
G01X490850Y166000D02*
X488550Y168300D01*
G01D02*
Y180673D01*
G01X480800Y160700D02*
Y150398D01*
G01D02*
X473410Y143008D01*
G01X505942Y196755D02*
X502216Y200481D01*
G01D02*
Y202550D01*
G01D02*
X500461Y204305D01*
G01D02*
X498386D01*
G01D02*
X486097Y216594D01*
G01X498400Y201950D02*
X489651D01*
G01D02*
X488462Y200761D01*
G01X488550Y180673D02*
X488462Y180761D01*
G01X486350Y374460D02*
X492110D01*
G01D02*
X493700Y376050D01*
G01D02*
Y378662D01*
G01X470970Y352630D02*
X492030D01*
G01D02*
X534500Y395100D01*
G01X493700Y378662D02*
X494908Y379870D01*
G01X496446Y785030D02*
X493125Y781709D01*
G01D02*
X490726D01*
G01D02*
X489522Y780505D01*
G01D02*
Y780127D01*
G01X491906Y775148D02*
X490061Y776993D01*
G01D02*
Y779588D01*
G01D02*
X489522Y780127D01*
G01X495906Y771648D02*
Y768598D01*
G01X503906Y775148D02*
X502440Y776614D01*
G01Y780192D02*
X504126Y781878D01*
G01X503906Y774941D02*
X502068Y773103D01*
G01D02*
Y765681D01*
G01D02*
X502044Y765657D01*
G01D02*
Y765135D01*
G01X501566Y787298D02*
Y781819D01*
G01D02*
X500778Y781031D01*
G01X499906Y775148D02*
Y780159D01*
G01D02*
X500778Y781031D01*
G01X499006Y787298D02*
Y781888D01*
G01D02*
X497910Y780792D01*
G01D02*
Y778824D01*
G01X495906Y775148D02*
X493408Y777646D01*
G01D02*
Y778813D01*
G01X497910Y778824D02*
X497834Y778900D01*
G01D02*
X493495D01*
G01D02*
X493408Y778813D01*
G01X487906Y775148D02*
X485199D01*
G01D02*
X482925Y777422D01*
G01D02*
X484017Y778514D01*
G01D02*
Y779898D01*
G01D02*
X484830Y780711D01*
G01X488778Y783442D02*
X487003Y781667D01*
G01D02*
X485786D01*
G01D02*
X484830Y780711D01*
G01X499906Y771648D02*
Y768531D01*
G01X496446Y787298D02*
Y785030D01*
G01X499006Y809498D02*
Y813444D01*
G01D02*
X498990Y813460D01*
G01D02*
Y815510D01*
G01D02*
X497000Y817500D01*
G01X493886Y787298D02*
Y785094D01*
G01D02*
X492234Y783442D01*
G01D02*
X488778D01*
G01X491326Y787298D02*
X487944D01*
G01D02*
X485254Y789988D01*
G01D02*
X482239D01*
G01D02*
X480445Y788194D01*
G01D02*
Y784920D01*
G01D02*
X480100Y784575D01*
G01X501566Y809498D02*
Y804566D01*
G01D02*
X501000Y804000D01*
G01D02*
X494582D01*
G01D02*
X492082Y801500D01*
G01D02*
X487000D01*
G01X501566Y809498D02*
Y812900D01*
G01D02*
X500415Y814051D01*
G01D02*
Y817532D01*
G01X495978Y820681D02*
Y818522D01*
G01D02*
X497000Y817500D01*
G01X506056Y826250D02*
X500807Y831499D01*
G01X504406Y824394D02*
X500700Y828100D01*
G01X500100Y820650D02*
Y818209D01*
G01D02*
X500415Y817894D01*
G01D02*
Y817532D01*
G01X504406Y820648D02*
X500102D01*
G01D02*
X500100Y820650D01*
G01X505500Y107980D02*
Y25500D01*
G01X536809Y21664D02*
X520578Y37895D01*
G01D02*
Y66230D01*
G01X502425Y107785D02*
Y47425D01*
G01X520578Y66230D02*
X524151Y69803D01*
G01X504430Y151750D02*
X509295D01*
G01D02*
X509403Y151642D01*
G01X535960Y151999D02*
Y152360D01*
G01D02*
X538500Y154900D01*
G01X534962Y159035D02*
X533118Y157191D01*
G01D02*
Y155318D01*
G01D02*
X532560Y154760D01*
G01D02*
Y152046D01*
G01X530152Y175634D02*
Y170571D01*
G01D02*
X526550Y166969D01*
G01D02*
Y165815D01*
G01Y161815D02*
Y165815D01*
G01X530050Y157715D02*
Y152587D01*
G01D02*
X529176Y151713D01*
G01X507700Y171550D02*
X507222Y171072D01*
G01D02*
X505275D01*
G01D02*
X503975Y172372D01*
G01X507700Y168050D02*
Y164720D01*
G01D02*
X513278Y159142D01*
G01X526550Y157715D02*
Y158315D01*
G01D02*
X530050Y161815D01*
G01X515935Y211965D02*
Y208950D01*
G01D02*
X511459Y204474D01*
G01D02*
Y202172D01*
G01X546180Y203627D02*
X524227D01*
G01D02*
X517355Y196755D01*
G01D02*
X505942D01*
G01X522278Y175634D02*
X516911D01*
G01D02*
X510095Y182450D01*
G01D02*
X507300D01*
G01X505050Y186500D02*
Y184700D01*
G01D02*
X507300Y182450D01*
G01Y178950D02*
Y175500D01*
G01X519159Y202072D02*
Y211519D01*
G01X511742Y215594D02*
X512306D01*
G01D02*
X515935Y211965D01*
G01X519159Y211519D02*
X521742Y214102D01*
G01D02*
Y215594D01*
G01X519906Y771648D02*
X521600Y769954D01*
G01D02*
Y766594D01*
G01D02*
X519906Y764900D01*
G01X503906Y771648D02*
Y768598D01*
G01X515906Y771648D02*
X519257Y768297D01*
G01D02*
X519748D01*
G01X514366Y784788D02*
X519458Y779696D01*
G01D02*
Y779247D01*
G01X519906Y775148D02*
Y778799D01*
G01D02*
X519458Y779247D01*
G01X502440Y776614D02*
Y780192D01*
G01X504126Y781878D02*
Y787298D01*
G01X503906Y775148D02*
Y774941D01*
G01X511806Y784538D02*
X515278Y781066D01*
G01D02*
Y779198D01*
G01X515906Y775148D02*
Y778570D01*
G01D02*
X515278Y779198D01*
G01X511906Y775148D02*
Y778093D01*
G01D02*
X511484Y778515D01*
G01D02*
X510822Y779177D01*
G01D02*
Y779863D01*
G01D02*
X509246Y781439D01*
G01D02*
Y781700D01*
G01Y787298D02*
Y781700D01*
G01X506686Y787298D02*
Y780623D01*
G01D02*
X507729Y779580D01*
G01D02*
Y778198D01*
G01X507906Y775148D02*
Y778021D01*
G01D02*
X507729Y778198D01*
G01X511906Y771648D02*
X513962Y769592D01*
G01D02*
Y767497D01*
G01D02*
X515650Y765809D01*
G01D02*
Y764500D01*
G01X528100Y775050D02*
Y778835D01*
G01D02*
X528179Y778914D01*
G01D02*
Y782555D01*
G01X523906Y775148D02*
X528002D01*
G01D02*
X528100Y775050D01*
G01X516926Y784946D02*
X521714Y780158D01*
G01D02*
X523825D01*
G01D02*
X526222Y782555D01*
G01D02*
X528179D01*
G01X507906Y771648D02*
Y768531D01*
G01X504278Y779198D02*
X505891Y777585D01*
G01D02*
Y777316D01*
G01D02*
X506068Y777139D01*
G01D02*
Y773486D01*
G01D02*
X507906Y771648D01*
G01X523906D02*
X522068Y773486D01*
G01D02*
Y776503D01*
G01D02*
X524094Y778529D01*
G01D02*
X524795D01*
G01X514366Y787298D02*
Y784788D01*
G01X511806Y787298D02*
Y784538D01*
G01Y809498D02*
Y812597D01*
G01D02*
X516610Y817401D01*
G01X509246Y809498D02*
Y814389D01*
G01D02*
X509855Y814998D01*
G01X512390Y817533D02*
X509855Y814998D01*
G01X503745Y816869D02*
Y815682D01*
G01X504126Y809498D02*
Y812879D01*
G01D02*
X503763Y813242D01*
G01D02*
Y815664D01*
G01D02*
X503745Y815682D01*
G01X516926Y809498D02*
Y812526D01*
G01D02*
X517900Y813500D01*
G01D02*
X520700D01*
G01D02*
X521425Y814225D01*
G01D02*
X521708D01*
G01D02*
X523019Y815536D01*
G01D02*
Y815819D01*
G01D02*
X524700Y817500D01*
G01X519486Y809498D02*
X520398D01*
G01D02*
X528100Y817200D01*
G01X506686Y809498D02*
Y813000D01*
G01D02*
X507200Y813514D01*
G01D02*
Y817413D01*
G01X521982Y817664D02*
X520781Y816463D01*
G01X514366Y809498D02*
Y812967D01*
G01D02*
X516389Y814990D01*
G01D02*
X519308D01*
G01D02*
X520781Y816463D01*
G01X516926Y787298D02*
Y784946D01*
G01X532906Y824148D02*
X535948D01*
G01D02*
X540200Y828400D01*
G01X528906Y824148D02*
X529148D01*
G01D02*
X534543Y829543D01*
G01X536500Y831500D02*
X534543Y829543D01*
G01X508500Y824150D02*
X506400Y826250D01*
G01D02*
X506056D01*
G01X523700Y829700D02*
Y825354D01*
G01D02*
X524906Y824148D01*
G01X532217Y839013D02*
X530811Y837607D01*
G01D02*
Y836811D01*
G01D02*
X523700Y829700D01*
G01X532650Y881382D02*
Y839446D01*
G01D02*
X532217Y839013D01*
G01X516610Y817401D02*
X516943D01*
G01X520906Y820648D02*
X520190D01*
G01D02*
X516943Y817401D01*
G01X512579Y824100D02*
X511900D01*
G01D02*
X508579Y827421D01*
G01X516679Y820600D02*
X515772D01*
G01D02*
X513984Y818812D01*
G01D02*
X513951D01*
G01D02*
X512716Y817577D01*
G01D02*
Y817550D01*
G01Y817577D02*
Y817580D01*
G01D02*
X512669Y817533D01*
G01D02*
X512390D01*
G01X516679Y824100D02*
X516079D01*
G01D02*
X512679Y827500D01*
G01X508500Y820650D02*
X507549D01*
G01D02*
X506306Y819407D01*
G01D02*
X506283D01*
G01D02*
X503745Y816869D01*
G01X504406Y824148D02*
Y824394D01*
G01X528906Y820648D02*
X527848D01*
G01D02*
X526744Y819544D01*
G01D02*
Y819293D01*
G01D02*
X526311Y818860D01*
G01D02*
X526060D01*
G01D02*
X524700Y817500D01*
G01X520906Y824148D02*
X519200Y825854D01*
G01D02*
Y832100D01*
G01D02*
X523300Y836200D01*
G01D02*
X527500D01*
G01X528100Y817200D02*
X528106D01*
G01D02*
X528504Y817598D01*
G01D02*
X528906D01*
G01X532906Y820648D02*
X531956D01*
G01D02*
X528906Y817598D01*
G01X507200Y817413D02*
X507044Y817569D01*
G01X512579Y820600D02*
X512300D01*
G01D02*
X510100Y818400D01*
G01D02*
X508031D01*
G01D02*
X507200Y817569D01*
G01D02*
X507044D01*
G01X524906Y820648D02*
X523948D01*
G01D02*
X521982Y818682D01*
G01D02*
Y817664D01*
G01X538977Y883677D02*
X535540Y880240D01*
G01D02*
Y871551D01*
G01D02*
X540200Y866891D01*
G01X535827Y887970D02*
Y882543D01*
G01D02*
X534075Y880791D01*
G01D02*
Y871000D01*
G01D02*
X536500Y868575D01*
G01X532678Y887970D02*
Y881410D01*
G01D02*
X532650Y881382D01*
G01X688000Y21664D02*
X536809D01*
G01X571809Y59800D02*
X567458Y64151D01*
G01D02*
Y69803D01*
G01X554250Y137597D02*
X557532D01*
G01D02*
X558220Y136909D01*
G01X549100Y126900D02*
X548900Y127100D01*
G01D02*
Y131720D01*
G01D02*
X550730Y133550D01*
G01X561648Y175634D02*
Y170770D01*
G01D02*
X564483Y167935D01*
G01X571400Y164750D02*
X568215Y167935D01*
G01D02*
X564483D01*
G01X563100Y161250D02*
X558600Y165750D01*
G01D02*
Y166770D01*
G01D02*
X558121Y167249D01*
G01X561600Y154800D02*
Y155100D01*
G01D02*
X563100Y156600D01*
G01D02*
Y161250D01*
G01X553774Y175634D02*
Y171089D01*
G01D02*
X555282Y169581D01*
G01D02*
X558572D01*
G01D02*
X563100Y165053D01*
G01D02*
Y164750D01*
G01X567200D02*
X563100D01*
G01X538500Y154900D02*
X541037D01*
G01D02*
X545337Y159200D01*
G01D02*
X552150D01*
G01D02*
X554500Y161550D01*
G01X545900Y175634D02*
Y172800D01*
G01D02*
X550200Y168500D01*
G01D02*
Y165250D01*
G01D02*
X550400Y165050D01*
G01X554500D02*
X555550D01*
G01D02*
X556638Y163962D01*
G01D02*
Y160062D01*
G01D02*
X558100Y158600D01*
G01X550400Y165050D02*
X554500D01*
G01X570754Y147365D02*
X567831Y144442D01*
G01D02*
Y144423D01*
G01D02*
X566531Y143123D01*
G01X538375Y163463D02*
Y159122D01*
G01D02*
X538462Y159035D01*
G01X538375Y163463D02*
X539378D01*
G01D02*
X542490Y160351D01*
G01X538026Y175634D02*
Y169412D01*
G01D02*
X542490Y164948D01*
G01D02*
Y163851D01*
G01X569522Y175634D02*
X573727D01*
G01X554641Y212088D02*
X546180Y203627D01*
G01X569522Y192366D02*
Y201672D01*
G01D02*
X570100Y202250D01*
G01X554641Y287310D02*
Y212088D01*
G01X545062Y344538D02*
Y306503D01*
G01D02*
X556312Y295253D01*
G01D02*
Y288981D01*
G01D02*
X554641Y287310D01*
G01X561300Y369500D02*
Y370100D01*
G01D02*
X563531Y372331D01*
G01D02*
Y373330D01*
G01X560531Y364180D02*
Y368731D01*
G01D02*
X561300Y369500D01*
G01X541400Y368580D02*
X548531D01*
G01X541400D02*
Y348200D01*
G01D02*
X545062Y344538D01*
G01X540500Y761000D02*
X543800Y757700D01*
G01D02*
X589100D01*
G01X544000Y761000D02*
X545875Y759125D01*
G01D02*
X581625D01*
G01X547395Y761198D02*
X547418Y761175D01*
G01D02*
X575075D01*
G01X540200Y828400D02*
Y837200D01*
G01Y866891D02*
Y837200D01*
G01X536500Y868575D02*
Y831500D01*
G01X538977Y887970D02*
Y883677D01*
G01X606643Y42015D02*
X588858Y59800D01*
G01D02*
X571809D01*
G01X573727Y175634D02*
X575600Y173761D01*
G01D02*
Y164650D01*
G01X591571Y206500D02*
X589713Y208358D01*
G01D02*
Y211308D01*
G01X598808Y205137D02*
X592934D01*
G01D02*
X591571Y206500D01*
G01X573151Y211067D02*
Y205301D01*
G01D02*
X570100Y202250D01*
G01X576100Y234500D02*
Y232300D01*
G01D02*
X578157Y230243D01*
G01D02*
X578219D01*
G01D02*
X579854Y228608D01*
G01D02*
X581313D01*
G01X589713Y215308D02*
Y211308D01*
G01X593213D02*
X594521Y210000D01*
G01D02*
X596253D01*
G01X602808Y213937D02*
X608699D01*
G01X597700Y747900D02*
X629500Y779700D01*
G01X629900Y776900D02*
X599200Y746200D01*
G01X589100Y757700D02*
X638470Y807070D01*
G01X581625Y759125D02*
X628148Y805648D01*
G01X630400Y783700D02*
X596300Y749600D01*
G01X575075Y761175D02*
X614444Y800544D01*
G01X687984Y23696D02*
X617191D01*
G01D02*
X606643Y34244D01*
G01D02*
Y42015D01*
G01X689157Y25121D02*
X617782D01*
G01D02*
X608068Y34835D01*
G01D02*
Y63197D01*
G01D02*
X610766Y65895D01*
G01D02*
Y69803D01*
G01X635482Y207733D02*
X637229Y209480D01*
G01X608699Y213937D02*
X615598Y207038D01*
G01D02*
X620743D01*
G01D02*
X623313Y209608D01*
G01X631363Y228358D02*
Y225708D01*
G01D02*
X632449Y224622D01*
G01X637229Y209480D02*
X644849D01*
G01X640633Y221799D02*
X635272D01*
G01D02*
X632449Y224622D01*
G01X612406Y232984D02*
X615687D01*
G01D02*
X616813Y231858D01*
G01D02*
X619363D01*
G01X631363D02*
X634613D01*
G01D02*
X637063Y229408D01*
G01X627363Y231858D02*
X631363D01*
G01X627363D02*
X623363D01*
G01D02*
X619363D01*
G01X612406Y234952D02*
X616807D01*
G01D02*
X616872Y235017D01*
G01D02*
X616970D01*
G01X622113Y238108D02*
X619113Y235108D01*
G01D02*
X617061D01*
G01D02*
X616970Y235017D01*
G01X604950Y344200D02*
X608090Y341060D01*
G01D02*
Y338070D01*
G01D02*
Y334110D01*
G01X632000Y329100D02*
Y324350D01*
G01Y333850D02*
Y329100D01*
G01X632750Y341033D02*
Y338100D01*
G01D02*
X632000Y337350D01*
G01X632016Y346807D02*
Y343800D01*
G01D02*
X632750Y343066D01*
G01D02*
Y341033D01*
G01X604950Y344200D02*
Y348200D01*
G01X623207Y353647D02*
X617748D01*
G01D02*
X612901Y348800D01*
G01D02*
X609050D01*
G01D02*
X608450Y348200D01*
G01X632600Y372042D02*
X632016Y371458D01*
G01D02*
Y366393D01*
G01X632000Y375850D02*
Y372642D01*
G01D02*
X632600Y372042D01*
G01X620812Y378038D02*
X623000Y375850D01*
G01D02*
Y371016D01*
G01D02*
X624516Y369500D01*
G01D02*
X627000D01*
G01D02*
X628079Y368421D01*
G01D02*
Y366393D01*
G01X626110Y366593D02*
X625407D01*
G01D02*
X617000Y375000D01*
G01D02*
Y375850D01*
G01D02*
X619387Y378237D01*
G01X632000Y384100D02*
Y379350D01*
G01X627500Y383850D02*
Y379350D01*
G01D02*
X632000D01*
G01X623000Y386850D02*
Y387000D01*
G01D02*
X626900Y390900D01*
G01X623000Y386850D02*
Y385595D01*
G01D02*
X620812Y383407D01*
G01D02*
Y378038D01*
G01X617000Y386850D02*
X616850Y387000D01*
G01D02*
X613400D01*
G01X619387Y378237D02*
Y385113D01*
G01D02*
X617650Y386850D01*
G01D02*
X617000D01*
G01X629500Y779700D02*
X645000D01*
G01X645800Y776900D02*
X629900D01*
G01X645813Y823313D02*
X628148Y805648D01*
G01X645600Y783700D02*
X630400D01*
G01X644388Y830488D02*
X614444Y800544D01*
G01X709829Y26969D02*
X648797D01*
G01D02*
X641050Y34716D01*
G01D02*
Y56780D01*
G01D02*
X654073Y69803D01*
G01X659881Y197442D02*
Y196419D01*
G01D02*
X682000Y174300D01*
G01X663756Y204942D02*
Y208506D01*
G01D02*
X667250Y212000D01*
G01X644849Y209480D02*
X645200Y209831D01*
G01D02*
Y217232D01*
G01D02*
X640633Y221799D01*
G01X671000Y215000D02*
X670250D01*
G01D02*
X667250Y212000D01*
G01X663750D02*
X660700D01*
G01X647621Y340950D02*
X649083D01*
G01D02*
X649518Y341385D01*
G01D02*
Y343076D01*
G01D02*
X651042Y344600D01*
G01X645724Y345639D02*
Y341417D01*
G01D02*
X646191Y340950D01*
G01D02*
X647621D01*
G01X659750Y340100D02*
X655750D01*
G01D02*
Y344600D01*
G01X648500Y372000D02*
X642993Y366493D01*
G01D02*
Y363490D01*
G01X652250Y372100D02*
X648600D01*
G01D02*
X648500Y372000D01*
G01X655750Y376600D02*
Y372100D01*
G01Y376600D02*
X659750D01*
G01D02*
Y374555D01*
G01D02*
X660500Y373805D01*
G01D02*
Y372100D01*
G01X651042Y344600D02*
X652250D01*
G01X642993Y349710D02*
Y348370D01*
G01D02*
X645724Y345639D01*
G01X660100Y344600D02*
X655750D01*
G01X645000Y779700D02*
X645800Y780500D01*
G01X645900Y814500D02*
X647238Y815838D01*
G01D02*
Y861862D01*
G01X638470Y807070D02*
X645900Y814500D01*
G01X645800Y783900D02*
X645600Y783700D01*
G01X645813Y861271D02*
Y823313D01*
G01X644388Y860680D02*
Y830488D01*
G01X647238Y861862D02*
X646000Y863100D01*
G01D02*
Y875500D01*
G01D02*
X649213Y878713D01*
G01D02*
Y887970D01*
G01X646063D02*
Y877363D01*
G01D02*
X644575Y875875D01*
G01D02*
Y862509D01*
G01D02*
X645813Y861271D01*
G01X642914Y887970D02*
Y880481D01*
G01D02*
X644388Y879007D01*
G01D02*
Y876993D01*
G01D02*
X643150Y875755D01*
G01D02*
Y861918D01*
G01D02*
X644388Y860680D01*
G01X707833Y1831D02*
X688000Y21664D01*
G01X706903Y4777D02*
X687984Y23696D01*
G01X705610Y8668D02*
X689157Y25121D01*
G01X682000Y174300D02*
X731643Y124657D01*
G01X747640Y117960D02*
X674100Y191500D01*
G01X749065Y122336D02*
X688200Y183201D01*
G01X752900Y122900D02*
X694300Y181500D01*
G01X677756Y204942D02*
Y208506D01*
G01D02*
X681250Y212000D01*
G01X691756Y204942D02*
X692650Y205836D01*
G01D02*
Y212200D01*
G01X673881Y197442D02*
Y191719D01*
G01D02*
X674100Y191500D01*
G01X687881Y197442D02*
Y191519D01*
G01D02*
X688200Y191200D01*
G01Y183201D02*
Y191200D01*
G01X694300Y181500D02*
X693600D01*
G01D02*
X693300Y181200D01*
G01X687900Y208100D02*
Y210950D01*
G01X685000Y215000D02*
X684250D01*
G01D02*
X681250Y212000D01*
G01X687900Y210950D02*
X689150Y212200D01*
G01X677750Y212000D02*
X674500D01*
G01X704619Y860919D02*
Y826697D01*
G01D02*
X712495Y818821D01*
G01X705906Y883406D02*
X702493Y879993D01*
G01D02*
Y875607D01*
G01D02*
X707558Y870542D01*
G01X702756Y887970D02*
Y882272D01*
G01D02*
X701068Y880584D01*
G01D02*
Y874732D01*
G01D02*
X706100Y869700D01*
G01Y862400D02*
X704619Y860919D01*
G01X728461Y9807D02*
Y4246D01*
G01D02*
X729132Y3575D01*
G01X747540Y-9650D02*
X730730D01*
G01D02*
X728395Y-7315D01*
G01X718302Y6774D02*
X716305Y4777D01*
G01D02*
X706903D01*
G01X721122Y9594D02*
X718302Y6774D01*
G01X733382Y3881D02*
X732837Y4426D01*
G01D02*
Y9562D01*
G01X740822Y66D02*
X727479D01*
G01D02*
X723763Y-3650D01*
G01X717763D02*
X714105D01*
G01D02*
X713461Y-3006D01*
G01X725963Y2380D02*
X723775Y192D01*
G01D02*
X714971D01*
G01D02*
X713332Y1831D01*
G01D02*
X707833D01*
G01X726382Y12502D02*
Y2799D01*
G01D02*
X725963Y2380D01*
G01X716860Y44769D02*
X722594Y39035D01*
G01D02*
X731650D01*
G01D02*
X736234Y43619D01*
G01X736317Y35906D02*
Y32078D01*
G01D02*
X736513Y31882D01*
G01X740767Y36243D02*
X736654D01*
G01D02*
X736317Y35906D01*
G01X733050Y14000D02*
X732654D01*
G01D02*
X728461Y9807D01*
G01X733013Y31882D02*
Y31237D01*
G01D02*
X736500Y27750D01*
G01X749562Y38144D02*
X734887D01*
G01D02*
X733013Y36270D01*
G01D02*
Y31882D01*
G01X725314Y24751D02*
Y21505D01*
G01D02*
X724820Y21011D01*
G01D02*
Y18490D01*
G01X724409Y28613D02*
X722560Y26764D01*
G01D02*
X720570D01*
G01D02*
X718758Y24952D01*
G01D02*
Y22249D01*
G01D02*
X719008Y21999D01*
G01X723740Y9594D02*
X721122D01*
G01X724820Y14990D02*
Y10674D01*
G01D02*
X723740Y9594D01*
G01X736550Y14000D02*
Y13275D01*
G01D02*
X732837Y9562D01*
G01X720755Y14964D02*
Y13268D01*
G01D02*
X718343Y10856D01*
G01D02*
X711188D01*
G01D02*
X709000Y8668D01*
G01D02*
X705610D01*
G01X721890Y24887D02*
X721649Y24646D01*
G01D02*
Y19369D01*
G01D02*
X720700Y18420D01*
G01X729000Y24800D02*
Y24007D01*
G01D02*
X728960Y23967D01*
G01D02*
Y18580D01*
G01X720909Y28613D02*
X717698D01*
G01D02*
X717325Y28240D01*
G01X713375Y27952D02*
X710812D01*
G01D02*
X709829Y26969D01*
G01X713375Y27952D02*
X717037D01*
G01D02*
X717325Y28240D01*
G01X728960Y15080D02*
X726382Y12502D01*
G01X716860Y51796D02*
Y44769D01*
G01X736234Y43619D02*
Y45309D01*
G01D02*
X747900Y56975D01*
G01X744000Y94179D02*
X722131Y72310D01*
G01D02*
X711436D01*
G01D02*
X708024Y68898D01*
G01X724890Y59880D02*
X724880Y59890D01*
G01D02*
X720840D01*
G01D02*
X716860Y55910D01*
G01D02*
Y55860D01*
G01X734880Y63910D02*
Y64450D01*
G01D02*
X738220Y67790D01*
G01D02*
Y68350D01*
G01D02*
X736990Y69580D01*
G01D02*
X734391D01*
G01D02*
X733709Y68898D01*
G01X732900Y44900D02*
Y48385D01*
G01D02*
X742367Y57852D01*
G01X718500Y68500D02*
X718102Y68898D01*
G01D02*
X714024D01*
G01X714250Y64000D02*
X718500Y68250D01*
G01D02*
Y68500D01*
G01X730021Y42235D02*
Y41829D01*
G01D02*
X730450Y41400D01*
G01D02*
X731999D01*
G01D02*
X734738Y44139D01*
G01D02*
Y45829D01*
G01D02*
X747309Y58400D01*
G01X727709Y68898D02*
X745500Y86689D01*
G01X731643Y124657D02*
X737598D01*
G01D02*
X745328Y116927D01*
G01X712495Y818821D02*
Y816195D01*
G01X706163Y860447D02*
Y827337D01*
G01D02*
X714900Y818600D01*
G01X705906Y887970D02*
Y883406D01*
G01X707558Y870542D02*
Y861842D01*
G01D02*
X706163Y860447D01*
G01X706100Y869700D02*
Y862400D01*
G01X746329Y-7789D02*
X750082Y-4036D01*
G01D02*
Y8072D01*
G01X775460Y3095D02*
X771715Y6840D01*
G01X751729Y7703D02*
Y-5461D01*
G01D02*
X747540Y-9650D01*
G01X770134Y9125D02*
X764698Y3689D01*
G01D02*
Y0D01*
G01X740882Y6D02*
X740822Y66D01*
G01X750082Y8072D02*
X756200Y14190D01*
G01D02*
Y20000D01*
G01D02*
X759850Y23650D01*
G01D02*
Y26200D01*
G01X743250Y33760D02*
X740767Y36243D01*
G01X759850Y35100D02*
Y33182D01*
G01D02*
X761638Y31394D01*
G01D02*
Y23422D01*
G01D02*
X757626Y19410D01*
G01D02*
Y13600D01*
G01D02*
X751729Y7703D01*
G01X756350Y26200D02*
X755046D01*
G01D02*
X752606Y28640D01*
G01D02*
X749750D01*
G01X762250Y40625D02*
X763400Y39475D01*
G01D02*
Y35200D01*
G01X752043Y40625D02*
X749562Y38144D01*
G01X778275Y9125D02*
X770134D01*
G01X749750Y31200D02*
X753750D01*
G01D02*
X754405Y30545D01*
G01D02*
X756192D01*
G01D02*
X756565Y30918D01*
G01X756350Y35100D02*
X756808Y34642D01*
G01D02*
Y31161D01*
G01D02*
X756565Y30918D01*
G01X752300Y16200D02*
X747650Y11550D01*
G01D02*
X742700D01*
G01X764150Y26200D02*
Y24350D01*
G01D02*
X772300Y16200D01*
G01X757250Y64000D02*
X758000Y64750D01*
G01D02*
Y68500D01*
G01D02*
X757602Y68898D01*
G01D02*
X753394D01*
G01X767450Y74000D02*
Y68465D01*
G01X767300Y78800D02*
Y74150D01*
G01D02*
X767450Y74000D01*
G01X747900Y56975D02*
X758118D01*
G01D02*
X767450Y66307D01*
G01D02*
Y68465D01*
G01X741600Y41000D02*
X741500Y41100D01*
G01D02*
X741000D01*
G01D02*
X739750Y42350D01*
G01D02*
Y44500D01*
G01X762250Y40625D02*
X752043D01*
G01X756050Y53800D02*
X760084D01*
G01X754750Y44500D02*
X751125D01*
G01D02*
X747250Y40625D01*
G01X756050Y53800D02*
Y45800D01*
G01D02*
X754750Y44500D01*
G01X742367Y57852D02*
X744815Y60300D01*
G01D02*
X756509D01*
G01D02*
X760238Y64029D01*
G01D02*
Y69427D01*
G01D02*
X753512Y76153D01*
G01X761200Y75900D02*
Y73960D01*
G01D02*
X763147Y72013D01*
G01D02*
Y65169D01*
G01X747309Y58400D02*
X756625D01*
G01D02*
X763147Y64922D01*
G01D02*
Y65169D01*
G01X747394Y68898D02*
Y106794D01*
G01X773638Y82700D02*
X771200D01*
G01D02*
X767300Y78800D01*
G01X745328Y108760D02*
X744000Y107432D01*
G01D02*
Y94179D01*
G01X773617Y104731D02*
X769981D01*
G01D02*
X769400Y104150D01*
G01X765300D02*
X769400D01*
G01X753512Y76153D02*
Y81056D01*
G01D02*
X756756Y84300D01*
G01D02*
X760300D01*
G01D02*
X761350Y85350D01*
G01D02*
Y86500D01*
G01X773638Y90380D02*
X765230D01*
G01D02*
X761350Y86500D01*
G01X773638Y85260D02*
X771160D01*
G01D02*
X761800Y75900D01*
G01D02*
X761200D01*
G01X745500Y86689D02*
Y106916D01*
G01D02*
X747640Y109056D01*
G01X747394Y106794D02*
X749065Y108465D01*
G01X773638Y92940D02*
X767460D01*
G01D02*
X766000Y94400D01*
G01X761350Y94700D02*
X765700D01*
G01D02*
X766000Y94400D01*
G01X761350Y94700D02*
Y90600D01*
G01X773638Y95500D02*
X770766D01*
G01D02*
X766683Y99583D01*
G01X761350Y98800D02*
X765900D01*
G01D02*
X766683Y99583D01*
G01X761350Y102900D02*
Y98800D01*
G01X766000Y85700D02*
X768120Y87820D01*
G01D02*
X773638D01*
G01X761350Y82300D02*
Y80950D01*
G01D02*
X759600Y79200D01*
G01X761350Y82300D02*
X762600D01*
G01D02*
X766000Y85700D01*
G01X773880Y121780D02*
X771800Y119700D01*
G01D02*
Y116800D01*
G01D02*
X770162Y115162D01*
G01D02*
X762888D01*
G01D02*
X759250Y118800D01*
G01X751300Y115000D02*
X752500Y116200D01*
G01D02*
X757900D01*
G01D02*
X759250Y117550D01*
G01D02*
Y118800D01*
G01X745328Y116927D02*
Y108760D01*
G01X768950Y133500D02*
Y138850D01*
G01D02*
X768700Y139100D01*
G01X776538Y126900D02*
X771450D01*
G01D02*
X768950Y129400D01*
G01D02*
Y133500D01*
G01Y121200D02*
Y118750D01*
G01D02*
X767600Y117400D01*
G01X776538Y124340D02*
X769910D01*
G01D02*
X768950Y125300D01*
G01D02*
Y121200D01*
G01X747640Y109056D02*
Y113479D01*
G01D02*
X747637Y113482D01*
G01D02*
Y116518D01*
G01D02*
X747640Y116521D01*
G01D02*
Y117960D01*
G01X749065Y108465D02*
Y114070D01*
G01D02*
X749062Y114073D01*
G01D02*
Y115927D01*
G01D02*
X749065Y115930D01*
G01D02*
Y122336D01*
G01X755750Y118800D02*
X752900Y121650D01*
G01D02*
Y122900D01*
G01X775460Y0D02*
Y3095D01*
G01X807963Y7400D02*
X803264Y2701D01*
G01D02*
Y0D01*
G01X783300Y1100D02*
Y4100D01*
G01D02*
X778275Y9125D01*
G01X813214Y38497D02*
X801060Y26343D01*
G01X797560D02*
Y18360D01*
G01D02*
X795300Y16100D01*
G01X809750Y20550D02*
X805300Y16100D01*
G01X785300D02*
Y18900D01*
G01D02*
X791800Y25400D01*
G01D02*
Y25850D01*
G01X798350Y74200D02*
X795550Y71400D01*
G01D02*
X786807D01*
G01D02*
X782551Y67144D01*
G01X798516Y74200D02*
X802200Y77884D01*
G01X778800Y66388D02*
Y69115D01*
G01D02*
X779752Y70067D01*
G01X784150Y74100D02*
X786850Y76800D01*
G01X779752Y70067D02*
X781158Y71473D01*
G01D02*
X781523D01*
G01D02*
X784150Y74100D01*
G01X778350Y74000D02*
X776217Y71867D01*
G01D02*
Y71610D01*
G01D02*
X774392Y69785D01*
G01D02*
Y67104D01*
G01D02*
X775381Y66115D01*
G01X778350Y74000D02*
X784490Y80140D01*
G01X786333Y66963D02*
X788970Y69600D01*
G01D02*
X800800D01*
G01D02*
X806750Y75550D01*
G01X798350Y74200D02*
X798516D01*
G01X802200Y77884D02*
Y82800D01*
G01D02*
X799740Y85260D01*
G01D02*
X795838D01*
G01X773638Y98060D02*
X773500Y98198D01*
G01D02*
Y104614D01*
G01D02*
X773617Y104731D01*
G01X786850Y76800D02*
X799100D01*
G01D02*
X800775Y78475D01*
G01D02*
Y80901D01*
G01D02*
X798976Y82700D01*
G01D02*
X795838D01*
G01X784490Y80140D02*
X795838D01*
G01X806750Y90600D02*
X803700D01*
G01D02*
X802600Y89500D01*
G01X795838Y90380D02*
X801720D01*
G01D02*
X802600Y89500D01*
G01X806750Y82400D02*
X805800D01*
G01D02*
X800380Y87820D01*
G01D02*
X795838D01*
G01X776538Y121780D02*
X773880D01*
G01X806402Y118898D02*
X803520Y121780D01*
G01D02*
X798738D01*
G01X781100Y135150D02*
X785150D01*
G01D02*
X786200Y136200D01*
G01X776538Y129460D02*
Y134688D01*
G01D02*
X777050Y135200D01*
G01D02*
X781050D01*
G01D02*
X781100Y135150D01*
G01X826700Y2000D02*
X819097D01*
G01D02*
Y2080D01*
G01D02*
X817500Y3677D01*
G01D02*
Y5200D01*
G01D02*
X815200Y7500D01*
G01X815634Y0D02*
X809713D01*
G01D02*
X807514Y2199D01*
G01X830500Y20800D02*
X831700D01*
G01D02*
X836317Y25417D01*
G01D02*
Y29400D01*
G01X830252Y17750D02*
Y20552D01*
G01D02*
X830500Y20800D01*
G01X822252Y17750D02*
X824297Y19795D01*
G01D02*
Y25605D01*
G01D02*
X824462Y25770D01*
G01D02*
X825385Y26693D01*
G01D02*
X828996D01*
G01D02*
X830226Y25463D01*
G01D02*
X832196D01*
G01D02*
X833167Y26434D01*
G01D02*
Y29400D01*
G01X815200Y7500D02*
X815100Y7400D01*
G01D02*
X807963D01*
G01X813214Y38497D02*
Y40735D01*
G01X839467Y29400D02*
Y22167D01*
G01D02*
X838252Y20952D01*
G01D02*
Y20800D01*
G01Y17750D02*
Y20800D01*
G01X828283Y24734D02*
X826252Y22703D01*
G01D02*
Y17750D01*
G01X828283Y24734D02*
X829879Y23138D01*
G01D02*
X831960D01*
G01D02*
X834742Y25920D01*
G01D02*
Y29400D01*
G01X837892D02*
Y24976D01*
G01D02*
X834500Y21584D01*
G01D02*
Y20800D01*
G01X834252Y17750D02*
Y20552D01*
G01D02*
X834500Y20800D01*
G01X815500Y20550D02*
X809750D01*
G01X824118Y55116D02*
Y59693D01*
G01D02*
X824450Y60025D01*
G01X824118Y51129D02*
Y55116D01*
G01Y51129D02*
X820018D01*
G01X839467Y51600D02*
Y64434D01*
G01D02*
X844212Y69179D01*
G01X813214Y40735D02*
X813962Y41483D01*
G01D02*
Y65487D01*
G01D02*
X823551Y75076D01*
G01X840597Y78097D02*
X835492Y72992D01*
G01X834742Y51600D02*
Y72242D01*
G01D02*
X835492Y72992D01*
G01X824118Y47629D02*
Y44398D01*
G01D02*
X823996Y44276D01*
G01X816950Y63900D02*
X828225D01*
G01D02*
X828700Y63425D01*
G01D02*
Y48800D01*
G01X836317Y51600D02*
Y69489D01*
G01D02*
X842707Y75879D01*
G01X846235Y75247D02*
X839289Y68301D01*
G01X837892Y51600D02*
Y66904D01*
G01D02*
X839289Y68301D01*
G01X820018Y47629D02*
Y44248D01*
G01D02*
X820004Y44234D01*
G01X808114Y67634D02*
X809825Y69345D01*
G01D02*
Y69359D01*
G01D02*
X816600Y76134D01*
G01X838850Y105600D02*
X843820Y110570D01*
G01X823551Y75076D02*
Y80551D01*
G01X835350Y105600D02*
X835500Y105450D01*
G01D02*
Y100500D01*
G01X835350Y105600D02*
X833128D01*
G01D02*
X833098Y105630D01*
G01D02*
X831310D01*
G01X806750Y90600D02*
Y86500D01*
G01Y75550D02*
Y82400D01*
G01X816600Y83025D02*
X813125Y86500D01*
G01D02*
X810250D01*
G01X816600Y76134D02*
Y83025D01*
G01X808663Y118898D02*
X806402D01*
G01X808663D02*
Y115563D01*
G01D02*
X807900Y114800D01*
G01X840000Y742500D02*
X830569Y751931D01*
G01X844000Y744500D02*
X828394Y760106D01*
G01X837000Y735500D02*
Y739138D01*
G01D02*
X833086Y743052D01*
G01X822441Y753697D02*
X833086Y743052D01*
G01X828300Y880000D02*
Y767700D01*
G01D02*
X848000Y748000D01*
G01X825175Y880991D02*
Y757325D01*
G01D02*
X830569Y751931D01*
G01X838000Y798500D02*
Y764500D01*
G01D02*
X844500Y758000D01*
G01X826600Y880400D02*
Y761900D01*
G01D02*
X828394Y760106D01*
G01X822441Y887970D02*
Y753697D01*
G01X848000Y808500D02*
X838000Y798500D01*
G01X831890Y887970D02*
Y883590D01*
G01D02*
X828300Y880000D01*
G01X825591Y887970D02*
Y881407D01*
G01D02*
X825175Y880991D01*
G01X828741Y887970D02*
Y882541D01*
G01D02*
X826600Y880400D01*
G01X849631Y5499D02*
X851199Y3931D01*
G01D02*
X853680D01*
G01D02*
X853681Y3932D01*
G01D02*
X854453D01*
G01X849581Y7337D02*
Y5549D01*
G01D02*
X849631Y5499D01*
G01X951182Y-6345D02*
X852707D01*
G01D02*
X851934Y-5572D01*
G01D02*
Y-1815D01*
G01X845934D02*
Y-4548D01*
G01D02*
X849156Y-7770D01*
G01D02*
X951773D01*
G01X875457Y-1435D02*
X872850D01*
G01X876865Y6435D02*
X872850D01*
G01D02*
Y7270D01*
G01X865250Y40000D02*
X869159D01*
G01D02*
X869250Y39909D01*
G01X865250Y36000D02*
Y40000D01*
G01X870435Y41000D02*
X869344Y39909D01*
G01D02*
X869250D01*
G01X867500Y20250D02*
Y16250D01*
G01X863300Y23575D02*
X866625Y20250D01*
G01D02*
X867500D01*
G01X850300Y14250D02*
X849100Y13050D01*
G01D02*
Y7818D01*
G01D02*
X849581Y7337D01*
G01X850300Y14250D02*
X848700Y15850D01*
G01D02*
X848650D01*
G01D02*
X848200Y16300D01*
G01D02*
Y19160D01*
G01D02*
X847213Y20147D01*
G01D02*
Y21587D01*
G01D02*
X844187Y24613D01*
G01D02*
Y29400D01*
G01X845762D02*
Y25538D01*
G01D02*
X848554Y22746D01*
G01D02*
X849812D01*
G01D02*
X851558Y21000D01*
G01D02*
X854052D01*
G01D02*
X854252Y20800D01*
G01X854400Y17750D02*
Y20652D01*
G01D02*
X854252Y20800D01*
G01X842612Y29400D02*
Y23240D01*
G01D02*
X845052Y20800D01*
G01X846252Y17750D02*
Y19092D01*
G01D02*
X845674Y19670D01*
G01D02*
Y20178D01*
G01D02*
X845052Y20800D01*
G01X873250Y22375D02*
Y25400D01*
G01D02*
X871374Y27276D01*
G01D02*
X868819D01*
G01X867500Y23750D02*
Y25957D01*
G01D02*
X868819Y27276D01*
G01X865250Y32000D02*
X868063Y34813D01*
G01D02*
X869192D01*
G01D02*
X869195Y34816D01*
G01X865250Y28000D02*
Y32000D01*
G01X875000Y36000D02*
X870383D01*
G01D02*
X869199Y34816D01*
G01D02*
X869195D01*
G01X867500Y12750D02*
X869500Y14750D01*
G01D02*
Y15200D01*
G01D02*
X870600Y16300D01*
G01D02*
Y18915D01*
G01X872850Y7270D02*
X867500Y12620D01*
G01D02*
Y12750D01*
G01X841037Y29400D02*
Y22015D01*
G01D02*
X841400Y21652D01*
G01D02*
Y21052D01*
G01D02*
X841652Y20800D01*
G01X842252Y17750D02*
Y19948D01*
G01D02*
X841652Y20548D01*
G01D02*
Y20800D01*
G01X850300Y17750D02*
Y19659D01*
G01D02*
X849051Y20908D01*
G01X863500Y59400D02*
X873500D01*
G01D02*
X884100Y70000D01*
G01X845762Y51600D02*
Y54468D01*
G01D02*
X850694Y59400D01*
G01D02*
X863500D01*
G01X875000Y41000D02*
X870435D01*
G01X865750Y48500D02*
X865700Y48450D01*
G01D02*
Y46662D01*
G01D02*
X865583Y46545D01*
G01D02*
Y45922D01*
G01D02*
X865533Y45872D01*
G01D02*
Y44084D01*
G01D02*
X865583Y44034D01*
G01X869250Y45400D02*
X866150Y48500D01*
G01D02*
X865750D01*
G01X874400Y45400D02*
X869250D01*
G01X871250Y52800D02*
Y51650D01*
G01D02*
X868800Y49200D01*
G01X865750Y52800D02*
Y52250D01*
G01D02*
X868800Y49200D01*
G01X874584Y62500D02*
X856000D01*
G01X844187Y51600D02*
Y54909D01*
G01D02*
X851778Y62500D01*
G01D02*
X856000D01*
G01X885042Y85292D02*
X873572Y73822D01*
G01D02*
X848855D01*
G01D02*
X844212Y69179D01*
G01X892900Y85300D02*
X873050Y65450D01*
G01D02*
X849950D01*
G01D02*
X848781Y64281D01*
G01X842612Y51600D02*
Y58112D01*
G01D02*
X848781Y64281D01*
G01X888600Y85700D02*
X871613Y68713D01*
G01D02*
X847713D01*
G01D02*
X842300Y63300D01*
G01X841037Y51600D02*
Y62037D01*
G01D02*
X842300Y63300D01*
G01X875000Y89220D02*
X872862Y87082D01*
G01D02*
X871696D01*
G01D02*
Y85597D01*
G01D02*
X864196Y78097D01*
G01D02*
X843654D01*
G01D02*
X843634Y78117D01*
G01D02*
X841780D01*
G01D02*
X841760Y78097D01*
G01D02*
X840597D01*
G01X875001Y86003D02*
X865670Y76672D01*
G01D02*
X843500D01*
G01D02*
X842707Y75879D01*
G01X878394Y85780D02*
X867861Y75247D01*
G01D02*
X846235D01*
G01X847710Y110570D02*
X862570D01*
G01D02*
X868000Y116000D01*
G01D02*
X868200D01*
G01X843820Y110570D02*
X847710D01*
G01X846730Y123128D02*
X846702Y123100D01*
G01D02*
Y117371D01*
G01X861310Y122608D02*
Y117810D01*
G01D02*
X861300Y117800D01*
G01X854510Y122640D02*
X854400Y122530D01*
G01D02*
Y117500D01*
G01X848000Y748000D02*
Y735500D01*
G01X869406Y748648D02*
Y745531D01*
G01X840500Y735500D02*
X840000Y736000D01*
G01D02*
Y742500D01*
G01X873352Y741450D02*
Y745320D01*
G01D02*
X873367Y745335D01*
G01X873406Y748574D02*
Y745374D01*
G01D02*
X873367Y745335D01*
G01X844000Y735500D02*
Y744500D01*
G01X865406Y748648D02*
Y745598D01*
G01X861406Y752148D02*
Y755198D01*
G01D02*
Y755406D01*
G01D02*
X864000Y758000D01*
G01X865946Y764298D02*
Y761353D01*
G01D02*
X865599Y761006D01*
G01D02*
Y759599D01*
G01D02*
X864000Y758000D01*
G01X860826Y764298D02*
Y762626D01*
G01D02*
X859938Y761738D01*
G01D02*
X857934D01*
G01D02*
X854049Y757853D01*
G01D02*
Y757573D01*
G01X848130Y789230D02*
X854860Y782500D01*
G01D02*
X855292D01*
G01X871066Y786498D02*
Y782066D01*
G01D02*
X870500Y781500D01*
G01D02*
X856292D01*
G01D02*
X855292Y782500D01*
G01X873406Y752074D02*
Y754576D01*
G01D02*
X872244Y755738D01*
G01X873626Y761418D02*
X872966Y760758D01*
G01D02*
Y757881D01*
G01D02*
X872244Y757159D01*
G01D02*
Y755738D01*
G01X863386Y764298D02*
Y761738D01*
G01D02*
X858679Y757031D01*
G01D02*
X858406D01*
G01D02*
X857406Y756031D01*
G01D02*
Y755198D01*
G01Y752148D02*
Y755198D01*
G01X871066Y764298D02*
Y759961D01*
G01D02*
X869562Y758457D01*
G01X869406Y752148D02*
Y758301D01*
G01D02*
X869562Y758457D01*
G01X868506Y764298D02*
Y761897D01*
G01D02*
X867024Y760415D01*
G01D02*
Y756210D01*
G01D02*
X867410Y755824D01*
G01X865406Y752148D02*
Y753159D01*
G01D02*
X867410Y755163D01*
G01D02*
Y755824D01*
G01X870900Y805350D02*
X871800Y804450D01*
G01D02*
Y799899D01*
G01D02*
X869756Y797855D01*
G01D02*
Y797648D01*
G01D02*
Y795053D01*
G01D02*
X870278Y794531D01*
G01X839990Y789230D02*
X848130D01*
G01X871066Y786498D02*
Y793743D01*
G01D02*
X870278Y794531D01*
G01X869756Y801148D02*
Y803344D01*
G01D02*
X864600Y808500D01*
G01D02*
X848000D01*
G01X865478Y797681D02*
Y795931D01*
G01D02*
X866878Y794531D01*
G01X868506Y786498D02*
Y792903D01*
G01D02*
X866878Y794531D01*
G01X883247Y7378D02*
X882334Y6465D01*
G01D02*
X877765D01*
G01D02*
X877300Y6000D01*
G01D02*
Y408D01*
G01D02*
X875457Y-1435D01*
G01X877300Y6000D02*
X876865Y6435D01*
G01X904750Y37000D02*
Y41000D01*
G01X889700Y23000D02*
X885250D01*
G01D02*
X880750Y18500D01*
G01X895300Y23000D02*
Y17950D01*
G01D02*
X896500Y16750D01*
G01X886520Y16752D02*
X883247Y13479D01*
G01D02*
Y7378D01*
G01X891301Y16627D02*
X886645D01*
G01D02*
X886520Y16752D01*
G01X899200Y65150D02*
X902000Y67950D01*
G01D02*
Y85841D01*
G01X884100Y70000D02*
X894350D01*
G01D02*
X899200Y65150D01*
G01X875000Y46000D02*
X874400Y45400D01*
G01X897600Y85500D02*
X883525Y71425D01*
G01D02*
X883509D01*
G01D02*
X874584Y62500D01*
G01X904750Y41000D02*
X902000D01*
G01D02*
X901000Y42000D01*
G01X895000Y41000D02*
X900000D01*
G01D02*
X901000Y42000D01*
G01X878800Y56350D02*
X875250Y52800D01*
G01D02*
X874750D01*
G01X878992Y61508D02*
X878800Y61316D01*
G01D02*
Y56350D01*
G01X885300Y64650D02*
X882134D01*
G01D02*
X878992Y61508D01*
G01X899200Y61650D02*
X902850D01*
G01D02*
X903000Y61500D01*
G01X892900Y64650D02*
X895900Y61650D01*
G01D02*
X899200D01*
G01X902000Y85841D02*
X901899Y85942D01*
G01X906500Y89750D02*
X906092D01*
G01D02*
X902142Y85800D01*
G01D02*
X902000Y85942D01*
G01D02*
X901899D01*
G01X910000Y85300D02*
X906230D01*
G01D02*
X906200Y85270D01*
G01X902000Y89750D02*
X897750Y85500D01*
G01D02*
X897600D01*
G01X888500Y89750D02*
Y89300D01*
G01D02*
X885326Y86126D01*
G01D02*
Y85576D01*
G01D02*
X885042Y85292D01*
G01X875000Y89750D02*
Y89220D01*
G01X897500Y89750D02*
X893050Y85300D01*
G01D02*
X892900D01*
G01X879500Y89750D02*
X879208D01*
G01D02*
X875461Y86003D01*
G01D02*
X875001D01*
G01X884000Y89750D02*
X882693D01*
G01D02*
X880905Y87962D01*
G01D02*
X880576D01*
G01D02*
X878394Y85780D01*
G01X893000Y89750D02*
X888950Y85700D01*
G01D02*
X888600D01*
G01X903937Y137795D02*
X901969Y135827D01*
G01X903937Y141732D02*
X901969Y139764D01*
G01X903937Y133858D02*
X901969Y131890D01*
G01X903937Y149606D02*
X901969Y147638D01*
G01X903937Y153543D02*
X901969Y151575D01*
G01X903937Y157480D02*
X901969Y155512D01*
G01X903937Y145669D02*
X901969Y143701D01*
G01X896780Y334690D02*
Y338544D01*
G01D02*
X894262Y341062D01*
G01D02*
Y347962D01*
G01X906500Y316500D02*
X904772Y314772D01*
G01D02*
X897728D01*
G01D02*
X896780Y315720D01*
G01D02*
Y318510D01*
G01X894220Y334690D02*
Y339088D01*
G01D02*
X892837Y340471D01*
G01D02*
Y354937D01*
G01X900250Y341600D02*
Y345600D01*
G01X896500Y342500D02*
X898100D01*
G01D02*
X899000Y341600D01*
G01D02*
X900250D01*
G01X899340Y334690D02*
Y338000D01*
G01D02*
X896500Y340840D01*
G01D02*
Y342500D01*
G01X900250Y350000D02*
Y354000D01*
G01X896500Y350200D02*
X896700Y350000D01*
G01D02*
X900250D01*
G01X894262Y347962D02*
X896500Y350200D01*
G01X900250Y358500D02*
Y363000D01*
G01X896200Y358300D02*
X896400Y358500D01*
G01D02*
X900250D01*
G01X892837Y354937D02*
X896200Y358300D01*
G01X920819Y598649D02*
X903187Y616281D01*
G01X922500Y591600D02*
X894700Y619400D01*
G01X920228Y597224D02*
X897500Y619952D01*
G01X903187Y616281D02*
Y810287D01*
G01X894700Y619400D02*
Y726700D01*
G01X921409Y600075D02*
X904612Y616872D01*
G01D02*
Y808012D01*
G01X897500Y619952D02*
Y733000D01*
G01X906450Y806900D02*
Y617050D01*
G01D02*
X922000Y601500D01*
G01X892100Y721100D02*
Y741338D01*
G01D02*
X891530Y741908D01*
G01D02*
Y746772D01*
G01D02*
X893406Y748648D01*
G01X891568Y750486D02*
X893406Y748648D01*
G01X889600Y739800D02*
X889406Y739994D01*
G01D02*
Y748648D01*
G01X888400Y721400D02*
X889600Y722600D01*
G01D02*
Y739800D01*
G01X894700Y726700D02*
X894090Y727310D01*
G01D02*
Y736690D01*
G01D02*
X895800Y738400D01*
G01X877406Y748648D02*
Y745406D01*
G01D02*
X877000Y745000D01*
G01X881406Y748648D02*
Y744822D01*
G01D02*
X878124Y741540D01*
G01D02*
Y741465D01*
G01D02*
X878064Y741405D01*
G01D02*
Y736106D01*
G01D02*
X881200Y732970D01*
G01D02*
Y721300D01*
G01X897500Y733000D02*
X896500Y734000D01*
G01X884700Y721100D02*
Y731489D01*
G01D02*
X879549Y736640D01*
G01D02*
Y740949D01*
G01D02*
X885406Y746806D01*
G01D02*
Y748648D01*
G01X891056Y755641D02*
X891568Y755129D01*
G01D02*
Y750486D01*
G01X873626Y764298D02*
Y761418D01*
G01X882227Y758835D02*
X879816Y756424D01*
G01D02*
Y755877D01*
G01X878746Y764298D02*
Y760476D01*
G01D02*
X879595Y759627D01*
G01D02*
X881435D01*
G01D02*
X882227Y758835D01*
G01X881406Y752148D02*
X879816Y753738D01*
G01D02*
Y755877D01*
G01X881306Y764298D02*
Y762130D01*
G01D02*
X882428Y761008D01*
G01D02*
Y760993D01*
G01D02*
X882861Y760560D01*
G01D02*
X883108D01*
G01D02*
X884067Y759601D01*
G01D02*
Y759482D01*
G01D02*
X884778Y758771D01*
G01D02*
Y756198D01*
G01X885406Y752148D02*
Y755570D01*
G01D02*
X884778Y756198D01*
G01X897600Y752050D02*
X897502Y752148D01*
G01D02*
X893406D01*
G01X886426Y764298D02*
Y761841D01*
G01D02*
X887767Y760500D01*
G01D02*
X890699D01*
G01D02*
X894465Y756734D01*
G01D02*
Y755501D01*
G01D02*
Y753207D01*
G01D02*
X893406Y752148D01*
G01X876186Y764298D02*
Y761686D01*
G01D02*
X876748Y761124D01*
G01D02*
Y756193D01*
G01D02*
X876036Y755481D01*
G01X877406Y752148D02*
X877206Y752348D01*
G01D02*
Y754311D01*
G01D02*
X876036Y755481D01*
G01X889406Y752148D02*
Y753471D01*
G01D02*
X889114Y753763D01*
G01D02*
Y757041D01*
G01D02*
X888087Y758068D01*
G01X883866Y764298D02*
Y762016D01*
G01D02*
X886685Y759197D01*
G01D02*
X886958D01*
G01D02*
X888087Y758068D01*
G01X873850Y801150D02*
Y811100D01*
G01D02*
X874570Y811820D01*
G01X903187Y810287D02*
X906092Y813192D01*
G01D02*
Y813687D01*
G01X882750Y817989D02*
Y809350D01*
G01D02*
X884017Y808083D01*
G01D02*
Y806057D01*
G01D02*
X886276Y803798D01*
G01X898406Y797648D02*
Y794494D01*
G01D02*
X898700Y794200D01*
G01D02*
Y788300D01*
G01X888986Y786498D02*
X896898D01*
G01D02*
X898700Y788300D01*
G01X890406Y797648D02*
Y793573D01*
G01D02*
X890049Y793216D01*
G01X883866Y786498D02*
Y789387D01*
G01D02*
X885340Y790861D01*
G01D02*
X886590D01*
G01D02*
X887390Y791661D01*
G01D02*
X888494D01*
G01D02*
X890049Y793216D01*
G01X877930Y796880D02*
Y800231D01*
G01D02*
X877949Y800250D01*
G01X877930Y796880D02*
Y795799D01*
G01D02*
X876186Y794055D01*
G01D02*
Y786498D01*
G01X894406Y801148D02*
Y818000D01*
G01X873850Y797650D02*
Y792250D01*
G01D02*
X873700Y792100D01*
G01X873626Y786498D02*
Y792026D01*
G01D02*
X873700Y792100D01*
G01X898406Y801148D02*
Y815706D01*
G01D02*
X898700Y816000D01*
G01X886288Y794372D02*
Y800286D01*
G01D02*
X886276Y800298D01*
G01X881306Y786498D02*
Y790006D01*
G01D02*
X883905Y792605D01*
G01D02*
X884758D01*
G01D02*
X886288Y794135D01*
G01D02*
Y794372D01*
G01X889920Y808230D02*
X889926Y807396D01*
G01D02*
X888278Y805748D01*
G01D02*
Y802300D01*
G01D02*
X886276Y800298D01*
G01X904612Y808012D02*
X906396Y809796D01*
G01D02*
Y810300D01*
G01X876470Y808710D02*
Y805229D01*
G01D02*
X877949Y803750D01*
G01X894406Y797648D02*
Y794706D01*
G01D02*
X894200Y794500D01*
G01X886426Y786498D02*
Y788681D01*
G01D02*
X887981Y790236D01*
G01D02*
X894065D01*
G01D02*
X894108Y790279D01*
G01X894200Y794500D02*
Y790371D01*
G01D02*
X894108Y790279D01*
G01X882290Y796770D02*
X882049Y797011D01*
G01D02*
Y800250D01*
G01X879696Y792164D02*
X882290Y794758D01*
G01D02*
Y796770D01*
G01X878746Y786498D02*
Y791214D01*
G01D02*
X879696Y792164D01*
G01X882049Y803750D02*
Y807061D01*
G01D02*
X881720Y807390D01*
G01X891137Y812539D02*
X892210Y811466D01*
G01D02*
Y802952D01*
G01D02*
X890406Y801148D01*
G01X890200Y819200D02*
Y813476D01*
G01D02*
X891137Y812539D01*
G01X888100Y823338D02*
X883226Y818464D01*
G01D02*
X883225D01*
G01D02*
X882750Y817989D01*
G01X923300Y9722D02*
X919486Y5908D01*
G01X930750Y27270D02*
Y23570D01*
G01D02*
X930720Y23540D01*
G01X950537Y32485D02*
X934328D01*
G01D02*
X930750Y28907D01*
G01D02*
Y27270D01*
G01X930720Y23540D02*
Y23185D01*
G01D02*
X927525Y19990D01*
G01D02*
X925706D01*
G01D02*
X922725Y17009D01*
G01D02*
X922717D01*
G01D02*
X919486Y13778D01*
G01X938000Y23250D02*
X939907D01*
G01D02*
X942031Y25374D01*
G01X938000Y23250D02*
X937338D01*
G01D02*
X932653Y18565D01*
G01D02*
X927201D01*
G01D02*
X923300Y14664D01*
G01D02*
Y9722D01*
G01X934881Y57322D02*
Y60271D01*
G01D02*
X930889Y64263D01*
G01D02*
X927943D01*
G01D02*
X925338Y66868D01*
G01D02*
Y76495D01*
G01X939064Y58104D02*
X930682Y66486D01*
G01D02*
X929616D01*
G01D02*
X928398Y67704D01*
G01D02*
Y70962D01*
G01X935350Y67400D02*
Y67725D01*
G01D02*
X932113Y70962D01*
G01D02*
X928398D01*
G01X920000Y89750D02*
X919050Y88800D01*
G01D02*
Y85500D01*
G01D02*
X918341D01*
G01D02*
X915908Y83067D01*
G01X911000Y89750D02*
Y86200D01*
G01D02*
X910100Y85300D01*
G01D02*
X910000D01*
G01X929000Y89750D02*
Y86806D01*
G01D02*
X929213Y86593D01*
G01D02*
Y82894D01*
G01D02*
X929060Y82741D01*
G01X928850Y78600D02*
X925400D01*
G01D02*
X925300Y78500D01*
G01X925338Y76495D02*
X925300Y76533D01*
G01D02*
Y78500D01*
G01X933500Y89750D02*
X931500Y87750D01*
G01D02*
Y85819D01*
G01D02*
X934779Y82540D01*
G01D02*
Y82801D01*
G01X934438Y86700D02*
X934779Y86359D01*
G01D02*
Y82801D01*
G01X938000Y89750D02*
Y85920D01*
G01D02*
X937642Y85562D01*
G01D02*
X939548Y83656D01*
G01D02*
Y82742D01*
G01D02*
X940377Y81913D01*
G01X915500Y89750D02*
Y88101D01*
G01D02*
X913979Y86580D01*
G01D02*
X912914Y85515D01*
G01D02*
Y83569D01*
G01D02*
X910754Y81409D01*
G01X924500Y89750D02*
Y86832D01*
G01D02*
X926093Y85239D01*
G01D02*
X924131D01*
G01D02*
X922015Y83123D01*
G01X923622Y133858D02*
X921654Y131890D01*
G01X931496Y141732D02*
X929528Y139764D01*
G01X911811Y133858D02*
X909843Y131890D01*
G01X915748Y133858D02*
X913780Y131890D01*
G01X927559Y141732D02*
X925591Y139764D01*
G01X919685Y141732D02*
X917717Y139764D01*
G01X911811Y141732D02*
X909843Y139764D01*
G01X915748Y137795D02*
X913780Y135827D01*
G01X923622Y141732D02*
X921654Y139764D01*
G01X927559Y145669D02*
X925591Y143701D01*
G01X915748Y145669D02*
X913780Y143701D01*
G01X915748Y149606D02*
X913780Y147638D01*
G01X911811Y161417D02*
X909843Y159449D01*
G01X931496Y157480D02*
X929528Y155512D01*
G01X919685Y161417D02*
X917717Y159449D01*
G01X927559Y157480D02*
X925591Y155512D01*
G01X935433Y157480D02*
X933465Y155512D01*
G01X915748Y157480D02*
X913780Y155512D01*
G01X923622Y153543D02*
X921654Y151575D01*
G01X919685Y157480D02*
X917717Y155512D01*
G01X931496Y153543D02*
X929528Y151575D01*
G01X939370Y157480D02*
X937402Y155512D01*
G01X911811Y145669D02*
X909843Y143701D01*
G01X927559Y149606D02*
X925591Y147638D01*
G01X923622Y157480D02*
X921654Y155512D01*
G01X915748Y161417D02*
X913780Y159449D01*
G01X915748Y153543D02*
X913780Y151575D01*
G01X919685Y153543D02*
X917717Y151575D01*
G01X935433Y153543D02*
X933465Y151575D01*
G01X911811Y157480D02*
X909843Y155512D01*
G01X1074910Y598650D02*
X921999Y598649D01*
G01D02*
X920819D01*
G01X1089400Y591600D02*
X922500D01*
G01X1074205Y600075D02*
X921409D01*
G01X1076225Y597225D02*
X931666Y597224D01*
G01D02*
X920228D01*
G01X922000Y601500D02*
X1072416D01*
G01X965000Y7473D02*
X951182Y-6345D01*
G01X951773Y-7770D02*
X966594Y7051D01*
G01X977000Y8546D02*
X971900Y13646D01*
G01D02*
Y18001D01*
G01D02*
X971902Y18003D01*
G01D02*
Y19525D01*
G01D02*
X971900Y19527D01*
G01D02*
Y21700D01*
G01D02*
X969932Y23668D01*
G01D02*
X959354D01*
G01D02*
X950537Y32485D01*
G01X963700Y21700D02*
X965000Y20400D01*
G01D02*
Y7473D01*
G01X966594Y7051D02*
Y15294D01*
G01D02*
X970064Y18764D01*
G01X958831Y64624D02*
X959300Y65093D01*
G01D02*
Y68600D01*
G01X955400Y68950D02*
X958950D01*
G01D02*
X959300Y68600D01*
G01X950120Y63525D02*
X942850D01*
G01X955331Y64624D02*
X954232Y63525D01*
G01D02*
X950120D01*
G01X942500Y114000D02*
Y102500D01*
G01Y93250D02*
Y102500D01*
G01X951500Y89750D02*
Y87800D01*
G01D02*
X953301Y85999D01*
G01D02*
Y85793D01*
G01D02*
Y84245D01*
G01D02*
X956313Y81233D01*
G01D02*
Y81319D01*
G01X942500Y89750D02*
Y86000D01*
G01D02*
X942800Y85700D01*
G01D02*
X945590Y82910D01*
G01D02*
Y82830D01*
G01X956687Y85482D02*
X958482D01*
G01D02*
X960522Y87522D01*
G01D02*
Y89645D01*
G01X956000Y89750D02*
X960417D01*
G01D02*
X960522Y89645D01*
G01X951500Y93250D02*
Y101500D01*
G01D02*
X953000Y103000D01*
G01D02*
Y108000D01*
G01X947000Y117866D02*
Y106000D01*
G01Y93250D02*
Y106000D01*
G01Y89750D02*
Y87100D01*
G01D02*
X948200Y85900D01*
G01D02*
X951070Y83030D01*
G01D02*
Y82791D01*
G01D02*
X950970D01*
G01X959055Y137795D02*
X961023Y135827D01*
G01X951181Y129921D02*
X953149Y127953D01*
G01X962992Y133858D02*
X964960Y131890D01*
G01X951181Y133858D02*
X953149Y131890D01*
G01X947244Y125984D02*
X945606Y124346D01*
G01D02*
Y117106D01*
G01D02*
X942500Y114000D01*
G01X947244Y129921D02*
X949212Y127953D01*
G01X974803Y133858D02*
X976771Y131890D01*
G01X959055Y133858D02*
X961023Y131890D01*
G01X962992Y141732D02*
X964960Y139764D01*
G01X966929Y133858D02*
X968897Y131890D01*
G01X959055Y141732D02*
X961023Y139764D01*
G01X947244Y141732D02*
X949212Y139764D01*
G01X955118Y137795D02*
X957086Y135827D01*
G01X947244Y122047D02*
X948882Y120409D01*
G01D02*
Y116118D01*
G01D02*
X953000Y112000D01*
G01D02*
Y108000D01*
G01X955118Y133858D02*
X957086Y131890D01*
G01X974803Y137795D02*
X976771Y135827D01*
G01X943307Y129921D02*
X941339Y127953D01*
G01X947244Y118110D02*
X947000Y117866D01*
G01X970866Y141732D02*
X972834Y139764D01*
G01X951181Y141732D02*
X953149Y139764D01*
G01X962992Y137795D02*
X964960Y135827D01*
G01X947244Y157480D02*
X949212Y155512D01*
G01X966929Y157480D02*
X968897Y155512D01*
G01X955118Y149606D02*
X957086Y147638D01*
G01X974803Y149606D02*
X976771Y147638D01*
G01X951181Y145669D02*
X953149Y143701D01*
G01X955118Y157480D02*
X957086Y155512D01*
G01X962992Y149606D02*
X964960Y147638D01*
G01X970866Y153543D02*
X972834Y151575D01*
G01X962992Y145669D02*
X964960Y143701D01*
G01X951181Y157480D02*
X953149Y155512D01*
G01X959055Y153543D02*
X961023Y151575D01*
G01X970866Y157480D02*
X972834Y155512D01*
G01X959055Y157480D02*
X961023Y155512D01*
G01X955118Y145669D02*
X957086Y143701D01*
G01X966929Y145669D02*
X968897Y143701D01*
G01X943307Y157480D02*
X941339Y155512D01*
G01X970866Y145669D02*
X972834Y143701D01*
G01X974803Y161417D02*
X976771Y159449D01*
G01X955118Y153543D02*
X957086Y151575D01*
G01X959055Y145669D02*
X961023Y143701D01*
G01X974803Y145669D02*
X976771Y143701D01*
G01X943307Y153543D02*
X941339Y151575D01*
G01X974803Y153543D02*
X976771Y151575D01*
G01X1001500Y611000D02*
X957500D01*
G01D02*
X953500Y607000D01*
G01X1002000D02*
X960500D01*
G01X1001984Y609000D02*
X958900D01*
G01D02*
X956900Y607000D01*
G01X1017554Y8546D02*
X977000D01*
G01X1000480Y41360D02*
X1003177Y38663D01*
G01D02*
X1005568D01*
G01D02*
X1007253Y36978D01*
G01D02*
Y34307D01*
G01X988167Y18587D02*
X992452D01*
G01D02*
X992540Y18675D01*
G01X1002253Y13707D02*
Y18895D01*
G01D02*
X1000667Y20481D01*
G01D02*
X994235D01*
G01D02*
X992540Y18786D01*
G01D02*
Y18675D01*
G01X992002Y37056D02*
X990834Y38224D01*
G01D02*
Y40879D01*
G01X992002Y37056D02*
X995186D01*
G01D02*
X997134Y39004D01*
G01D02*
X1000820D01*
G01D02*
X1002253Y37571D01*
G01D02*
Y34307D01*
G01X999753Y13707D02*
Y17144D01*
G01D02*
X999169Y17728D01*
G01D02*
X996129D01*
G01D02*
X992561Y14160D01*
G01D02*
X992461D01*
G01X1010357Y22640D02*
X1006498Y26499D01*
G01D02*
X996558D01*
G01D02*
X989409Y33648D01*
G01D02*
Y48479D01*
G01X1000480Y41812D02*
Y45497D01*
G01D02*
X1000683Y45700D01*
G01X1000480Y41812D02*
Y41360D01*
G01X990834Y40879D02*
X992531Y42576D01*
G01D02*
X995812D01*
G01D02*
X996230Y42994D01*
G01X989409Y48479D02*
X990628Y49698D01*
G01X982677Y141732D02*
X984645Y139764D01*
G01X978740Y133858D02*
X980708Y131890D01*
G01X986614Y133858D02*
X988582Y131890D01*
G01X978740Y137795D02*
X980708Y135827D01*
G01X990551Y141732D02*
X992519Y139764D01*
G01X986614Y153543D02*
X988582Y151575D01*
G01X978740Y157480D02*
X980708Y155512D01*
G01X978740Y161417D02*
X980708Y159449D01*
G01X978740Y153543D02*
X980708Y151575D01*
G01X1028741Y638241D02*
X1001500Y611000D01*
G01X1031900Y636900D02*
X1002000Y607000D01*
G01X1030201Y637217D02*
X1001984Y609000D01*
G01X1021310Y2024D02*
X1020500Y2834D01*
G01D02*
Y5600D01*
G01D02*
X1017554Y8546D01*
G01X1024810Y2024D02*
Y4490D01*
G01D02*
X1023600Y5700D01*
G01D02*
Y11500D01*
G01X1022711Y-4975D02*
X1024810Y-2876D01*
G01D02*
Y2024D01*
G01X1035642Y8542D02*
X1031265Y4165D01*
G01D02*
Y1702D01*
G01X1041108D02*
Y8987D01*
G01X1023600Y11500D02*
X1032276Y20176D01*
G01D02*
X1033747D01*
G01X1039917Y11296D02*
Y15095D01*
G01D02*
X1039675Y15337D01*
G01D02*
X1039437Y15575D01*
G01D02*
X1037230D01*
G01D02*
X1036064Y16741D01*
G01D02*
Y19216D01*
G01D02*
X1035104Y20176D01*
G01D02*
X1033747D01*
G01X1009753Y34307D02*
Y37862D01*
G01D02*
X1010676Y38785D01*
G01D02*
Y41512D01*
G01X1024330Y26232D02*
X1032882D01*
G01D02*
X1033571Y26921D01*
G01X1030139Y30209D02*
X1032301Y28047D01*
G01D02*
X1032445D01*
G01D02*
X1033571Y26921D01*
G01X1044464Y22640D02*
X1010357D01*
G01X1035642Y11076D02*
Y8542D01*
G01X1033017Y14743D02*
X1033022Y14738D01*
G01D02*
Y14578D01*
G01D02*
X1035642Y11958D01*
G01D02*
Y11076D01*
G01X1036692Y38477D02*
Y33737D01*
G01D02*
X1036866Y33563D01*
G01X1050765Y39228D02*
X1037443D01*
G01D02*
X1036692Y38477D01*
G01X1028330Y35032D02*
Y41229D01*
G01Y35032D02*
X1031897D01*
G01D02*
X1033366Y33563D01*
G01X1041108Y8987D02*
X1043417Y11296D01*
G01X1033000Y66250D02*
Y49451D01*
G01D02*
X1033517Y48934D01*
G01X1024432Y43718D02*
X1027659Y46945D01*
G01D02*
X1034127D01*
G01D02*
X1035355Y48173D01*
G01D02*
Y48210D01*
G01D02*
X1035409Y48264D01*
G01D02*
Y48500D01*
G01D02*
X1038052Y51143D01*
G01D02*
Y57740D01*
G01D02*
X1036750Y59042D01*
G01D02*
Y68750D01*
G01D02*
X1052240Y84240D01*
G01X1028330Y41229D02*
X1028815Y41714D01*
G01X1032500Y105250D02*
Y106500D01*
G01D02*
X1034500Y108500D01*
G01X1024000Y105250D02*
Y108500D01*
G01X1020000Y105250D02*
X1019900Y105350D01*
G01D02*
Y108500D01*
G01X1015948Y105250D02*
Y108500D01*
G01X1028000Y105250D02*
Y107914D01*
G01D02*
X1027483Y108431D01*
G01X1034500Y108500D02*
X1035710Y109710D01*
G01D02*
Y115410D01*
G01D02*
X1037900Y117600D01*
G01D02*
Y246368D01*
G01X1024000Y108500D02*
Y111000D01*
G01D02*
X1035050Y122050D01*
G01D02*
Y247550D01*
G01X1019900Y108500D02*
Y109700D01*
G01D02*
X1028226Y118026D01*
G01D02*
X1028342D01*
G01D02*
X1033625Y123309D01*
G01D02*
Y250525D01*
G01X1031400Y112500D02*
X1030883Y111983D01*
G01D02*
Y108438D01*
G01X1015948Y108500D02*
X1016800D01*
G01D02*
X1031800Y123500D01*
G01D02*
Y251400D01*
G01X1036475Y246959D02*
Y121459D01*
G01D02*
X1027483Y112467D01*
G01D02*
Y108431D01*
G01X1037900Y246368D02*
X1207932Y416400D01*
G01X1035050Y247550D02*
X1208500Y421000D01*
G01X1033625Y250525D02*
X1201000Y417900D01*
G01X1031800Y251400D02*
X1196600Y416200D01*
G01X1209016Y419500D02*
X1036475Y246959D01*
G01X1028741Y887970D02*
Y638241D01*
G01X1031900Y824884D02*
Y636900D01*
G01X1030201Y881501D02*
Y637217D01*
G01X1031626Y880869D02*
Y825158D01*
G01D02*
X1031900Y824884D01*
G01X1035040Y884283D02*
X1031626Y880869D01*
G01X1031890Y887970D02*
Y883190D01*
G01D02*
X1030201Y881501D01*
G01X1035040Y887970D02*
Y884283D01*
G01X1075809Y5500D02*
Y500D01*
G01D02*
Y-1896D01*
G01D02*
X1077558Y-3645D01*
G01X1069200Y-4200D02*
Y5056D01*
G01D02*
X1069131Y5125D01*
G01D02*
Y7363D01*
G01X1050951Y1702D02*
Y6449D01*
G01D02*
X1048736Y8664D01*
G01X1075819Y26950D02*
X1076108D01*
G01X1075819Y22450D02*
Y26950D01*
G01X1056650Y36200D02*
Y38000D01*
G01D02*
X1058150Y39500D01*
G01D02*
Y44400D01*
G01X1068673Y24395D02*
Y27768D01*
G01D02*
X1067495Y28946D01*
G01D02*
X1065657D01*
G01X1068809Y16792D02*
X1068759D01*
G01D02*
X1066672Y18879D01*
G01D02*
Y22344D01*
G01D02*
X1068673Y24345D01*
G01D02*
Y24395D01*
G01X1069131Y7363D02*
Y9601D01*
G01D02*
X1064361Y14371D01*
G01D02*
Y27272D01*
G01D02*
X1059912Y31721D01*
G01D02*
Y42669D01*
G01X1076374Y39554D02*
X1073453D01*
G01D02*
X1071559Y37660D01*
G01D02*
Y35329D01*
G01X1076374Y35054D02*
X1071834D01*
G01D02*
X1071559Y35329D01*
G01X1051250Y22200D02*
X1050150Y21100D01*
G01D02*
X1046004D01*
G01D02*
X1044464Y22640D01*
G01X1056200Y10100D02*
X1055100Y9000D01*
G01D02*
X1051000D01*
G01D02*
X1048792Y11208D01*
G01D02*
X1048736D01*
G01Y8664D02*
Y11208D01*
G01X1056650Y28600D02*
Y29650D01*
G01D02*
X1053400Y32900D01*
G01D02*
Y36593D01*
G01D02*
X1050765Y39228D01*
G01X1054750Y22200D02*
Y24330D01*
G01D02*
X1056650Y26230D01*
G01D02*
Y28600D01*
G01X1043417Y11296D02*
Y15400D01*
G01D02*
X1043650Y15633D01*
G01X1070733Y41173D02*
X1069403D01*
G01D02*
X1065933Y44643D01*
G01D02*
Y48832D01*
G01X1070733Y41173D02*
X1073766D01*
G01D02*
X1078721Y46128D01*
G01X1050216Y50022D02*
X1053428D01*
G01D02*
X1054750Y48700D01*
G01X1050216Y50022D02*
Y49234D01*
G01D02*
X1052975Y46475D01*
G01D02*
X1056075D01*
G01D02*
X1058150Y44400D01*
G01X1051000Y41500D02*
Y43500D01*
G01D02*
X1049500Y45000D01*
G01X1042669Y68898D02*
Y66831D01*
G01D02*
X1045000Y64500D01*
G01X1049350Y64100D02*
X1045400D01*
G01D02*
X1045000Y64500D01*
G01X1059912Y42669D02*
X1060138Y42895D01*
G01D02*
Y46812D01*
G01D02*
X1058250Y48700D01*
G01X1047500Y41500D02*
X1042900Y46100D01*
G01D02*
X1042600D01*
G01X1068354Y68898D02*
Y75047D01*
G01X1058110Y69355D02*
Y72110D01*
G01D02*
X1060000Y74000D01*
G01X1062354Y68898D02*
Y71646D01*
G01D02*
X1060000Y74000D01*
G01X1048669Y68898D02*
Y72369D01*
G01D02*
X1051850Y75550D01*
G01X1088039Y68898D02*
X1067500Y89437D01*
G01D02*
Y128750D01*
G01X1052240Y84240D02*
Y90155D01*
G01D02*
X1057000Y94915D01*
G01D02*
Y107700D01*
G01X1068354Y75047D02*
X1057431Y85970D01*
G01D02*
Y89182D01*
G01X1065500Y129915D02*
Y97251D01*
G01D02*
X1057431Y89182D01*
G01X1051850Y75550D02*
X1054627Y78327D01*
G01D02*
Y89543D01*
G01D02*
X1063688Y98604D01*
G01D02*
Y130119D01*
G01X1067500Y128750D02*
X1071330Y132580D01*
G01X1150500Y211750D02*
X1071330Y132580D01*
G01X1136000Y200415D02*
X1065500Y129915D01*
G01X1063688Y130119D02*
X1121500Y187931D01*
G01X1170473Y694213D02*
X1074910Y598650D01*
G01X1169000Y694870D02*
X1074205Y600075D01*
G01X1072416Y601500D02*
X1165375Y694459D01*
G01X1090750Y8895D02*
Y5000D01*
G01D02*
Y500D01*
G01X1084000D02*
X1079309D01*
G01X1087250D02*
X1084000D01*
G01X1097000Y1500D02*
X1097500D01*
G01D02*
X1104626Y8626D01*
G01X1077558Y-3645D02*
X1091855D01*
G01D02*
X1097000Y1500D01*
G01X1114000Y22625D02*
X1104425Y32200D01*
G01D02*
X1087039D01*
G01D02*
X1086613Y31774D01*
G01X1076108Y26950D02*
X1077946Y28788D01*
G01D02*
X1082022D01*
G01D02*
X1082047Y28763D01*
G01D02*
X1083569D01*
G01D02*
X1083594Y28788D01*
G01D02*
X1083627D01*
G01D02*
X1086613Y31774D01*
G01X1090929Y9074D02*
X1090750Y8895D01*
G01X1180035Y10051D02*
X1096087D01*
G01D02*
X1095923Y9887D01*
G01D02*
X1093363D01*
G01D02*
X1092550Y9074D01*
G01D02*
X1090929D01*
G01X1110454Y21200D02*
X1104214Y27440D01*
G01D02*
X1090370D01*
G01D02*
Y22940D01*
G01X1086475Y14177D02*
X1083264D01*
G01D02*
X1082974Y14467D01*
G01X1104626Y8626D02*
X1180626D01*
G01X1079226Y18266D02*
X1079485Y18525D01*
G01D02*
X1086677D01*
G01X1078589Y14070D02*
Y17629D01*
G01D02*
X1079226Y18266D01*
G01X1079874Y39554D02*
X1082044D01*
G01D02*
X1083379Y40889D01*
G01X1086870Y22940D02*
X1086060D01*
G01D02*
X1083500Y25500D01*
G01X1079319Y22450D02*
X1080450D01*
G01D02*
X1083500Y25500D01*
G01X1078302Y41482D02*
X1076374Y39554D01*
G01X1090754Y40883D02*
Y36383D01*
G01X1078721Y46128D02*
X1087592D01*
G01D02*
X1088005Y46541D01*
G01X1087254Y40883D02*
X1083385D01*
G01D02*
X1083379Y40889D01*
G01X1112272Y64292D02*
X1102980Y55000D01*
G01D02*
Y50096D01*
G01D02*
X1096053Y43169D01*
G01D02*
X1082879D01*
G01D02*
X1081192Y41482D01*
G01D02*
X1078302D01*
G01X1082039Y68898D02*
X1078437Y72500D01*
G01D02*
X1078000D01*
G01X1077750Y68500D02*
Y72250D01*
G01D02*
X1078000Y72500D01*
G01X1090754Y40883D02*
X1097056D01*
G01D02*
X1105441Y49268D01*
G01D02*
Y54768D01*
G01X1120200Y622400D02*
X1089400Y591600D01*
G01X1185499Y706499D02*
X1076225Y597225D01*
G01X1150409Y22625D02*
X1114000D01*
G01X1151000Y21200D02*
X1110454D01*
G01X1129466Y64292D02*
X1112272D01*
G01X1136000Y221250D02*
Y200415D01*
G01X1121500Y187931D02*
Y221250D01*
G01X1125375Y228750D02*
X1127500Y230875D01*
G01D02*
Y234500D01*
G01X1123750Y235000D02*
X1127000D01*
G01D02*
X1127500Y234500D01*
G01X1134187Y238517D02*
X1134394Y238724D01*
G01D02*
X1143724D01*
G01X1134250Y234500D02*
Y238454D01*
G01D02*
X1134187Y238517D01*
G01X1139875Y228750D02*
X1141500Y230375D01*
G01D02*
Y234000D01*
G01X1137750Y234500D02*
X1141000D01*
G01D02*
X1141500Y234000D01*
G01X1143000Y242000D02*
X1123184D01*
G01D02*
X1120205Y239021D01*
G01X1120250Y235000D02*
Y238976D01*
G01D02*
X1120205Y239021D01*
G01X1302300Y622400D02*
X1120200D01*
G01X1155775Y55591D02*
Y27991D01*
G01D02*
X1150409Y22625D01*
G01X1157200Y55000D02*
Y27400D01*
G01D02*
X1151000Y21200D01*
G01X1172773Y64292D02*
X1164476D01*
G01D02*
X1155775Y55591D01*
G01X1193991Y59500D02*
X1161700D01*
G01D02*
X1157200Y55000D01*
G01X1172773Y79252D02*
X1177325Y74700D01*
G01X1162660Y296693D02*
Y191307D01*
G01D02*
X1183332Y170635D01*
G01X1156000Y234500D02*
X1154375Y232875D01*
G01D02*
Y228750D01*
G01X1152250Y234500D02*
X1156000D01*
G01X1143724Y238724D02*
X1147000Y242000D01*
G01X1150500Y221250D02*
Y211750D01*
G01X1151000Y242000D02*
X1155000D01*
G01X1148750Y234500D02*
X1151000Y236750D01*
G01D02*
Y242000D01*
G01X1186767Y320800D02*
X1162660Y296693D01*
G01X1172500Y742500D02*
Y697568D01*
G01D02*
X1170473Y695541D01*
G01D02*
Y694213D01*
G01X1169000Y750500D02*
Y694870D01*
G01X1165375Y694459D02*
Y757000D01*
G01X1172500Y742500D02*
Y811400D01*
G01X1169000Y795550D02*
Y750500D01*
G01X1165375Y822391D02*
Y757000D01*
G01X1169700Y814200D02*
X1170575Y815075D01*
G01D02*
Y880641D01*
G01X1172500Y811400D02*
X1169700Y814200D01*
G01X1166800Y821800D02*
Y797750D01*
G01D02*
X1169000Y795550D01*
G01X1169150Y880050D02*
Y824150D01*
G01D02*
X1166800Y821800D01*
G01X1167586Y879037D02*
Y824602D01*
G01D02*
X1165375Y822391D01*
G01X1170575Y880641D02*
X1170473Y880743D01*
G01D02*
Y887970D01*
G01X1167323D02*
Y881877D01*
G01D02*
X1169150Y880050D01*
G01X1164174Y887970D02*
Y882449D01*
G01D02*
X1167586Y879037D01*
G01X1207248Y55460D02*
Y37264D01*
G01D02*
X1180035Y10051D01*
G01X1180626Y8626D02*
X1208673Y36673D01*
G01D02*
Y54869D01*
G01X1216080Y64292D02*
X1207248Y55460D01*
G01X1190900Y74700D02*
X1195800Y69800D01*
G01D02*
Y61309D01*
G01D02*
X1193991Y59500D01*
G01X1208673Y54869D02*
X1214804Y61000D01*
G01X1177325Y74700D02*
X1190900D01*
G01X1183332Y170635D02*
X1286385D01*
G01X1302992Y320800D02*
X1186767D01*
G01X1207932Y416400D02*
X1270450D01*
G01X1208500Y421000D02*
X1257500D01*
G01X1268880Y419500D02*
X1209016D01*
G01X1202675Y847309D02*
Y666475D01*
G01D02*
X1210000Y659150D01*
G01D02*
X1328150D01*
G01X1185499Y808649D02*
Y706499D01*
G01X1201250Y824400D02*
X1185499Y808649D01*
G01X1205525Y850159D02*
X1202675Y847309D01*
G01X1204100Y850750D02*
X1201250Y847900D01*
G01D02*
Y824400D01*
G01X1201969Y887970D02*
Y882669D01*
G01D02*
X1198556Y879256D01*
G01D02*
Y873160D01*
G01D02*
X1205525Y866191D01*
G01D02*
Y850159D01*
G01X1198819Y887970D02*
Y882119D01*
G01D02*
X1197131Y880431D01*
G01D02*
Y872569D01*
G01D02*
X1204100Y865600D01*
G01D02*
Y850750D01*
G01X1214804Y61000D02*
X1236400D01*
G01D02*
X1239600Y64200D01*
G01D02*
Y68900D01*
G01D02*
X1232900Y75600D01*
G01D02*
X1219732D01*
G01D02*
X1216080Y79252D01*
G01X1248234Y143195D02*
X1246218Y141179D01*
G01X1249679Y133345D02*
Y137718D01*
G01D02*
X1246218Y141179D01*
G01X1253719Y133345D02*
Y139037D01*
G01D02*
X1254956Y140274D01*
G01D02*
Y142088D01*
G01X1248234Y145217D02*
Y143195D01*
G01X1254956Y142088D02*
X1252173Y144871D01*
G01D02*
X1251801D01*
G01X1290050Y282250D02*
X1255000Y317300D01*
G01X1262500Y342250D02*
X1262600Y342350D01*
G01D02*
Y346000D01*
G01X1258500Y342250D02*
X1262500D01*
G01X1274500D02*
X1272500Y344250D01*
G01X1270500Y342250D02*
X1266500D01*
G01X1269940Y346000D02*
Y342810D01*
G01D02*
X1270500Y342250D01*
G01X1278500D02*
X1275060Y345690D01*
G01X1267380Y355300D02*
Y348380D01*
G01D02*
X1265000Y346000D01*
G01D02*
X1262600D01*
G01X1264820Y355300D02*
Y349320D01*
G01X1272500Y344250D02*
Y350000D01*
G01D02*
Y355300D01*
G01X1282500Y342250D02*
X1277620Y347130D01*
G01D02*
Y349500D01*
G01D02*
Y355300D01*
G01X1272500Y377500D02*
Y380600D01*
G01X1269940Y346000D02*
Y355300D01*
G01X1275060Y377500D02*
Y381840D01*
G01X1277620Y385120D02*
Y377500D01*
G01X1275060Y345690D02*
Y355300D01*
G01X1277500Y397750D02*
Y393750D01*
G01X1273500Y400500D02*
X1276250Y397750D01*
G01D02*
X1277500D01*
G01X1269500Y390250D02*
X1273500D01*
G01X1268400Y386100D02*
Y389150D01*
G01D02*
X1269500Y390250D01*
G01X1272500Y380600D02*
X1268400Y384700D01*
G01D02*
Y386100D01*
G01X1277500Y390250D02*
X1273400Y386150D01*
G01D02*
Y383500D01*
G01X1275060Y381840D02*
X1273400Y383500D01*
G01X1278000Y385500D02*
X1277620Y385120D01*
G01X1270450Y416400D02*
X1316700Y462650D01*
G01X1257500Y421000D02*
X1258000Y421500D01*
G01X1314500Y465120D02*
X1268880Y419500D01*
G01X1308000Y51484D02*
Y32000D01*
G01D02*
X1296606Y20606D01*
G01D02*
Y7874D01*
G01X1302606Y31496D02*
X1304000Y32890D01*
G01D02*
Y36250D01*
G01X1296606Y42106D02*
Y31496D01*
G01X1302606Y7874D02*
X1304000Y9268D01*
G01D02*
Y12750D01*
G01X1306188Y74188D02*
X1296606Y64606D01*
G01D02*
Y55118D01*
G01X1309038Y115820D02*
Y52522D01*
G01D02*
X1308000Y51484D01*
G01X1307613Y117033D02*
Y53113D01*
G01D02*
X1296606Y42106D01*
G01X1302606Y55118D02*
X1304000Y56512D01*
G01D02*
Y59750D01*
G01X1306188Y117908D02*
Y74188D01*
G01X1302606Y78740D02*
Y80506D01*
G01D02*
X1304000Y81900D01*
G01D02*
Y83250D01*
G01X1296606Y78740D02*
X1296310Y79036D01*
G01D02*
Y92955D01*
G01D02*
X1299933Y96578D01*
G01D02*
Y124200D01*
G01X1314930Y126650D02*
X1306188Y117908D01*
G01X1314064Y120825D02*
X1309038Y115820D01*
G01X1306970Y139185D02*
X1305712Y140443D01*
G01D02*
Y141101D01*
G01D02*
X1305710Y141103D01*
G01D02*
Y144320D01*
G01X1314992Y124412D02*
X1307613Y117033D01*
G01X1299933Y129548D02*
X1301543Y131158D01*
G01D02*
Y152335D01*
G01X1299933Y124200D02*
X1299720Y124413D01*
G01D02*
Y126545D01*
G01D02*
X1299933Y126758D01*
G01D02*
Y129548D01*
G01X1305418Y159835D02*
Y156557D01*
G01D02*
X1310776Y151199D01*
G01X1310060Y145310D02*
X1306700D01*
G01D02*
X1305710Y144320D01*
G01X1311262Y175228D02*
X1309695Y176795D01*
G01X1292545D02*
X1290978Y175228D01*
G01X1286385Y170635D02*
X1290978Y175228D01*
G01X1309695Y176795D02*
X1292545D01*
G01X1307000Y282250D02*
X1290050D01*
G01X1289250Y300000D02*
Y303650D01*
G01D02*
X1288900Y304000D01*
G01X1292750Y300000D02*
Y295000D01*
G01X1295600Y305182D02*
X1294282D01*
G01D02*
X1292750Y303650D01*
G01D02*
Y300000D01*
G01X1298300Y300700D02*
Y303400D01*
G01D02*
X1296518Y305182D01*
G01D02*
X1295600D01*
G01X1307100Y296700D02*
Y305600D01*
G01D02*
X1308362Y306862D01*
G01D02*
X1319751D01*
G01X1311000Y278750D02*
X1315000D01*
G01X1307000D02*
X1311000D01*
G01X1294500Y342250D02*
Y344550D01*
G01X1299000Y347500D02*
X1302500Y344000D01*
G01D02*
Y342250D01*
G01X1286500D02*
X1282170Y346580D01*
G01X1290500Y342250D02*
X1288275Y344475D01*
G01X1298500Y342250D02*
Y344500D01*
G01X1324500Y342308D02*
X1302992Y320800D01*
G01X1282740Y383000D02*
Y377500D01*
G01X1293280Y345770D02*
X1290730D01*
G01D02*
X1285300Y351200D01*
G01D02*
Y355300D01*
G01X1294500Y344550D02*
X1293280Y345770D01*
G01X1292980Y377500D02*
Y379980D01*
G01X1299000Y347500D02*
X1296000Y350500D01*
G01D02*
X1293000D01*
G01D02*
X1290420Y353080D01*
G01D02*
Y355300D01*
G01X1287860Y377500D02*
Y380610D01*
G01X1281900Y346580D02*
Y346850D01*
G01D02*
X1280180Y348570D01*
G01D02*
Y355300D01*
G01X1282170Y346580D02*
X1281900D01*
G01X1285300Y377500D02*
Y382300D01*
G01X1285760Y347120D02*
X1282870Y350010D01*
G01D02*
X1282740D01*
G01D02*
Y355300D01*
G01X1288275Y344475D02*
Y344605D01*
G01D02*
X1285760Y347120D01*
G01X1290420Y377500D02*
Y380571D01*
G01X1289960Y349900D02*
X1287860Y352000D01*
G01D02*
Y355300D01*
G01X1298500Y344500D02*
X1294000Y349000D01*
G01D02*
X1290860D01*
G01D02*
X1289960Y349900D01*
G01X1280180Y377500D02*
Y384680D01*
G01X1289500Y390250D02*
X1282740Y383490D01*
G01D02*
Y383000D01*
G01X1292980Y379980D02*
X1295375Y382375D01*
G01D02*
X1297625D01*
G01X1305500Y390250D02*
X1297625Y382375D01*
G01X1287860Y380610D02*
X1290125Y382875D01*
G01X1297500Y390250D02*
X1290125Y382875D01*
G01X1285300Y382300D02*
X1289500Y386500D01*
G01X1293500Y390250D02*
X1289750Y386500D01*
G01D02*
X1289500D01*
G01X1290420Y380571D02*
X1296349Y386500D01*
G01D02*
X1296500D01*
G01X1301500Y390250D02*
X1297750Y386500D01*
G01D02*
X1296500D01*
G01X1280180Y384680D02*
X1282000Y386500D01*
G01X1285500Y390250D02*
Y390000D01*
G01D02*
X1282000Y386500D01*
G01X1316700Y608000D02*
X1302300Y622400D01*
G01X1301000Y618500D02*
X1314500Y605000D01*
G01X1300000Y637000D02*
X1324500Y612500D01*
G01X1302128Y680617D02*
Y685500D01*
G01X1318500Y662000D02*
X1299500D01*
G01D02*
X1297500Y664000D01*
G01X1286800Y671100D02*
X1297325Y660575D01*
G01D02*
X1325975D01*
G01X1310128Y677117D02*
X1310078D01*
G01D02*
X1308506Y675545D01*
G01D02*
Y665701D01*
G01D02*
X1310207Y664000D01*
G01X1306128Y680617D02*
Y685628D01*
G01X1310128Y680617D02*
X1310209D01*
G01D02*
X1311966Y678860D01*
G01D02*
Y674035D01*
G01D02*
X1311017Y673086D01*
G01X1310128Y682289D02*
Y680617D01*
G01X1308108Y692767D02*
Y690207D01*
G01D02*
X1303401Y685500D01*
G01D02*
X1302128D01*
G01X1310668Y692767D02*
Y690168D01*
G01D02*
X1307000Y686500D01*
G01X1306128Y685628D02*
X1307000Y686500D01*
G01X1313228Y687357D02*
X1312132Y686261D01*
G01Y684293D02*
X1310128Y682289D01*
G01X1305548Y692767D02*
Y693452D01*
G01D02*
X1303500Y695500D01*
G01D02*
X1302000D01*
G01X1313228Y720272D02*
X1310500Y723000D01*
G01X1310200Y726150D02*
Y723300D01*
G01D02*
X1310500Y723000D01*
G01X1302562Y799262D02*
Y780438D01*
G01D02*
X1340500Y742500D01*
G01X1296562Y828662D02*
Y781823D01*
G01D02*
X1339910Y738475D01*
G01X1339901Y740500D02*
X1298800Y781601D01*
G01D02*
Y818400D01*
G01X1295137Y829253D02*
Y781232D01*
G01D02*
X1339320Y737049D01*
G01X1307038Y822862D02*
Y803738D01*
G01D02*
X1302562Y799262D01*
G01X1300483Y876818D02*
Y829485D01*
G01D02*
X1300500Y829401D01*
G01D02*
X1307038Y822862D01*
G01X1297525Y870811D02*
Y829625D01*
G01D02*
X1296562Y828662D01*
G01X1298800Y818400D02*
X1298950Y818550D01*
G01D02*
Y870220D01*
G01X1296100Y871402D02*
Y830216D01*
G01D02*
X1295137Y829253D01*
G01X1302756Y887970D02*
Y881655D01*
G01D02*
X1299962Y878861D01*
G01D02*
Y877339D01*
G01D02*
X1300483Y876818D01*
G01X1296457Y887970D02*
Y882682D01*
G01D02*
X1296989Y882150D01*
G01D02*
Y876080D01*
G01D02*
X1297525Y875544D01*
G01D02*
Y873527D01*
G01D02*
X1297531Y873521D01*
G01D02*
Y870817D01*
G01D02*
X1297525Y870811D01*
G01X1298950Y870220D02*
X1298956Y870226D01*
G01D02*
Y874112D01*
G01D02*
X1298950Y874118D01*
G01D02*
Y876135D01*
G01D02*
X1298500Y876585D01*
G01D02*
Y880015D01*
G01D02*
X1299607Y881122D01*
G01D02*
Y887970D01*
G01X1293308D02*
Y881900D01*
G01D02*
X1295564Y879644D01*
G01D02*
Y875490D01*
G01D02*
X1296100Y874953D01*
G01D02*
Y872936D01*
G01D02*
X1296106Y872930D01*
G01D02*
Y871408D01*
G01D02*
X1296100Y871402D01*
G01X1314930Y126650D02*
Y134850D01*
G01D02*
X1314470Y135310D01*
G01X1316049Y120821D02*
X1317240Y119630D01*
G01D02*
X1322980D01*
G01D02*
X1325220Y121870D01*
G01X1316049Y120821D02*
X1314064Y120825D01*
G01X1335071Y134361D02*
X1333926Y135506D01*
G01D02*
X1329876D01*
G01D02*
X1329618Y135248D01*
G01X1329095Y129370D02*
Y134725D01*
G01D02*
X1329618Y135248D01*
G01X1335071Y137861D02*
X1336478Y139268D01*
G01D02*
X1339471D01*
G01X1319875Y135104D02*
X1318030Y133259D01*
G01D02*
Y126090D01*
G01D02*
X1316352Y124412D01*
G01D02*
X1314992D01*
G01X1325530Y140759D02*
X1319875Y135104D01*
G01X1313560Y145310D02*
X1315250Y143620D01*
G01D02*
X1317400D01*
G01X1329405Y148259D02*
X1332261D01*
G01D02*
X1335100Y145420D01*
G01X1314276Y151199D02*
X1314738D01*
G01D02*
X1316590Y149347D01*
G01D02*
Y147210D01*
G01X1335100Y141920D02*
X1336070D01*
G01D02*
X1340130Y145980D01*
G01X1318750Y274500D02*
Y274750D01*
G01D02*
X1320500Y276500D01*
G01D02*
X1322000D01*
G01X1327357Y269156D02*
X1325232D01*
G01D02*
X1320888Y273500D01*
G01D02*
X1319750D01*
G01D02*
X1318750Y274500D01*
G01X1327357Y271124D02*
X1325280D01*
G01D02*
X1323838Y272566D01*
G01D02*
Y275000D01*
G01D02*
X1325161Y276323D01*
G01D02*
Y279162D01*
G01X1319751Y306862D02*
X1321400Y305213D01*
G01D02*
Y301650D01*
G01X1315000Y278750D02*
X1319000D01*
G01X1325161Y279162D02*
X1324564Y279759D01*
G01D02*
X1320910D01*
G01D02*
X1319851Y278700D01*
G01D02*
X1319050D01*
G01D02*
X1319000Y278750D01*
G01X1324500Y612500D02*
Y342308D01*
G01X1316700Y462650D02*
Y608000D01*
G01X1314500Y605000D02*
Y465120D01*
G01X1328150Y659150D02*
X1331000Y662000D01*
G01X1338128Y677117D02*
X1336795Y678450D01*
G01D02*
Y678729D01*
G01D02*
X1336290Y679234D01*
G01D02*
Y681972D01*
G01X1318128Y677117D02*
Y675037D01*
G01D02*
X1318528Y674637D01*
G01D02*
Y665521D01*
G01D02*
X1317007Y664000D01*
G01X1322400Y673050D02*
X1324100Y674750D01*
G01D02*
Y678700D01*
G01D02*
X1322183Y680617D01*
G01D02*
X1322128D01*
G01D02*
Y683598D01*
G01X1330128Y677117D02*
Y675342D01*
G01D02*
X1333308Y672162D01*
G01D02*
X1340761D01*
G01D02*
X1341736Y673137D01*
G01D02*
X1347348D01*
G01X1322128Y677117D02*
X1320290Y678955D01*
G01D02*
Y682877D01*
G01X1322128Y677117D02*
Y676928D01*
G01D02*
X1319953Y674753D01*
G01D02*
Y663453D01*
G01D02*
X1318500Y662000D01*
G01X1334128Y677117D02*
Y674000D01*
G01X1330128Y680617D02*
Y684039D01*
G01X1318128Y680617D02*
X1316662Y682083D01*
G01X1318128Y680617D02*
Y680410D01*
G01D02*
X1316290Y678572D01*
G01D02*
Y675620D01*
G01D02*
X1316216Y675546D01*
G01D02*
Y673308D01*
G01X1325975Y660575D02*
X1327200Y661800D01*
G01X1342300Y680250D02*
X1341933Y680617D01*
G01D02*
X1338128D01*
G01D02*
Y682026D01*
G01X1314128Y680617D02*
Y685628D01*
G01Y677117D02*
X1313607Y676596D01*
G01D02*
Y664000D01*
G01X1346757Y674562D02*
X1340562D01*
G01D02*
X1340000Y674000D01*
G01X1326128Y677117D02*
Y674000D01*
G01X1334128Y680617D02*
Y684944D01*
G01X1326128Y680617D02*
Y680567D01*
G01D02*
X1327966Y678729D01*
G01D02*
Y673938D01*
G01D02*
X1329496Y672408D01*
G01D02*
X1329579D01*
G01X1326758Y686678D02*
Y681247D01*
G01D02*
X1326128Y680617D01*
G01X1320908Y720708D02*
Y714967D01*
G01X1323468Y726968D02*
Y714967D01*
G01X1336290Y681972D02*
X1336703Y682385D01*
G01D02*
Y682617D01*
G01D02*
X1336795Y682709D01*
G01D02*
Y685141D01*
G01X1315788Y714967D02*
Y722212D01*
G01X1320908Y692767D02*
Y686092D01*
G01D02*
X1321928Y685072D01*
G01D02*
Y683798D01*
G01X1322128Y683598D02*
X1321928Y683798D01*
G01X1313228Y714967D02*
Y720272D01*
G01X1318348Y724848D02*
Y714967D01*
G01X1320290Y682877D02*
X1318500Y684667D01*
G01X1326028Y692767D02*
Y690007D01*
G01D02*
X1329500Y686535D01*
G01D02*
Y684667D01*
G01X1330128Y684039D02*
X1329500Y684667D01*
G01X1316662Y682083D02*
Y685661D01*
G01D02*
X1318348Y687347D01*
G01D02*
Y692767D01*
G01X1331148D02*
Y690366D01*
G01D02*
X1331197Y690317D01*
G01D02*
X1331246D01*
G01D02*
X1332563Y689000D01*
G01D02*
X1336401D01*
G01D02*
X1337439Y687962D01*
G01D02*
X1337538D01*
G01D02*
X1339934Y685566D01*
G01D02*
Y683832D01*
G01X1338128Y682026D02*
X1339934Y683832D01*
G01X1315788Y692767D02*
Y687288D01*
G01D02*
X1315000Y686500D01*
G01X1314128Y685628D02*
X1315000Y686500D01*
G01X1331148Y714967D02*
Y719648D01*
G01X1333708Y714967D02*
Y719609D01*
G01X1326028Y714967D02*
Y722559D01*
G01X1328588Y692767D02*
Y689463D01*
G01D02*
X1332031Y686020D01*
G01D02*
X1333052D01*
G01X1334128Y684944D02*
X1333052Y686020D01*
G01X1328588Y714967D02*
Y720588D01*
G01X1323468Y692767D02*
Y689968D01*
G01D02*
X1326758Y686678D01*
G01X1313228Y692767D02*
Y687357D01*
G01X1312132Y686261D02*
Y684293D01*
G01X1319500Y731500D02*
X1321440Y729560D01*
G01D02*
Y726980D01*
G01D02*
X1321675Y726745D01*
G01D02*
Y721475D01*
G01D02*
X1320908Y720708D01*
G01X1319500Y737000D02*
X1322865Y733635D01*
G01D02*
Y727571D01*
G01D02*
X1323468Y726968D01*
G01X1334128Y729617D02*
Y732667D01*
G01X1315788Y722212D02*
X1315000Y723000D01*
G01X1314628Y726117D02*
Y723372D01*
G01D02*
X1315000Y723000D01*
G01X1338128Y729617D02*
Y732872D01*
G01X1339910Y738475D02*
X1340640D01*
G01D02*
X1350338Y728777D01*
G01X1319500Y726000D02*
X1318348Y724848D01*
G01X1354850Y726281D02*
X1340631Y740500D01*
G01D02*
X1339901D01*
G01X1326128Y729617D02*
Y730428D01*
G01D02*
X1328290Y732590D01*
G01D02*
Y733428D01*
G01D02*
X1329862Y735000D01*
G01D02*
X1339500D01*
G01D02*
X1342000Y732500D01*
G01X1330128Y729617D02*
Y732667D01*
G01X1339320Y737049D02*
X1340050D01*
G01D02*
X1347200Y729899D01*
G01X1331148Y719648D02*
X1333500Y722000D01*
G01D02*
Y723000D01*
G01X1334128Y726117D02*
Y724128D01*
G01D02*
X1333500Y723500D01*
G01D02*
Y723000D01*
G01X1333708Y719609D02*
X1337099Y723000D01*
G01D02*
X1337500D01*
G01X1338128Y726117D02*
Y723628D01*
G01D02*
X1337500Y723000D01*
G01X1326100Y734150D02*
X1324290Y732340D01*
G01D02*
Y728162D01*
G01D02*
X1326128Y726324D01*
G01D02*
Y726117D01*
G01X1326028Y722559D02*
X1325600Y722987D01*
G01X1326128Y726117D02*
Y723515D01*
G01D02*
X1325600Y722987D01*
G01X1330128Y726117D02*
Y722128D01*
G01D02*
X1329500Y721500D01*
G01X1328588Y720588D02*
X1329500Y721500D01*
G01X1314628Y729617D02*
Y733000D01*
G01X1363168Y168102D02*
X1360004D01*
G01D02*
X1359128Y167226D01*
G01X1359124Y174870D02*
X1354449D01*
G01D02*
X1353445Y173866D01*
G01D02*
Y168972D01*
G01D02*
X1354971Y167446D01*
G01X1359011Y178934D02*
Y174983D01*
G01D02*
X1359124Y174870D01*
G01X1366668Y168102D02*
X1369726D01*
G01D02*
X1371541Y166287D01*
G01X1366668Y168102D02*
Y170722D01*
G01D02*
X1364343Y173047D01*
G01D02*
Y173852D01*
G01X1378998Y168228D02*
X1381264D01*
G01X1372093Y173852D02*
Y173230D01*
G01D02*
X1377095Y168228D01*
G01D02*
X1378998D01*
G01X1365804Y185197D02*
X1363041Y182434D01*
G01D02*
X1359011D01*
G01X1378134Y176959D02*
X1377457Y177636D01*
G01D02*
X1370679D01*
G01D02*
X1368218Y180097D01*
G01D02*
Y181352D01*
G01X1378134Y176959D02*
X1383023D01*
G01X1360250Y278500D02*
X1362000D01*
G01D02*
X1364000Y280500D01*
G01X1347348Y673137D02*
X1349463Y675252D01*
G01D02*
Y702888D01*
G01X1351500Y675000D02*
Y681468D01*
G01D02*
X1354850Y684818D01*
G01X1348038Y702297D02*
Y675843D01*
G01D02*
X1346757Y674562D01*
G01X1350338Y728777D02*
Y706500D01*
G01D02*
X1348669Y704831D01*
G01X1349463Y702888D02*
X1348625Y703726D01*
G01D02*
Y704787D01*
G01D02*
X1348669Y704831D01*
G01X1354850Y684818D02*
Y726281D01*
G01X1347200Y729899D02*
Y714299D01*
G01D02*
X1346662Y713761D01*
G01D02*
Y712239D01*
G01D02*
X1347200Y711701D01*
G01D02*
Y706527D01*
G01D02*
X1346431Y705758D01*
G01D02*
Y703904D01*
G01D02*
X1348038Y702297D01*
G01X1381264Y168228D02*
X1387196Y174160D01*
G01X1383319Y177216D02*
X1383340D01*
G01X1383319D02*
X1385467Y179364D01*
G01D02*
Y180543D01*
G01X1383023Y176959D02*
X1383319Y177255D01*
G01D02*
Y177216D01*
M02*
